G04 ================== begin FILE IDENTIFICATION RECORD ==================*
G04 Layout Name:  12004-1.brd*
G04 Film Name:    L6*
G04 File Format:  Gerber RS274X*
G04 File Origin:  Cadence Allegro 16.2-S033*
G04 Origin Date:  Tue Oct 16 14:36:08 2012*
G04 *
G04 Layer:  VIA CLASS/L6*
G04 Layer:  PIN/L6*
G04 Layer:  ETCH/L6*
G04 Layer:  DRAWING FORMAT/LAYER_PCB_STORY*
G04 Layer:  DRAWING FORMAT/LAYER_L6*
G04 *
G04 Offset:    (0.00 0.00)*
G04 Mirror:    No*
G04 Mode:      Positive*
G04 Rotation:  0*
G04 FullContactRelief:  No*
G04 UndefLineWidth:     6.00*
G04 ================== end FILE IDENTIFICATION RECORD ====================*
%FSLAX35Y35*MOIN*%
%IR0*IPPOS*OFA0.00000B0.00000*MIA0B0*SFA1.00000B1.00000*%
%ADD10C,.01*%
%ADD13C,.02*%
%ADD11C,.022*%
%ADD15C,.05*%
%ADD19C,.061*%
%ADD17C,.055*%
%ADD14C,.046*%
%ADD12C,.028*%
%ADD16C,.213*%
%ADD18C,.115*%
%ADD20C,.012*%
%ADD21C,.04*%
%ADD22C,.025*%
%ADD23C,.004*%
%ADD24C,.006*%
%ADD25C,.0045*%
%ADD41C,.03004*%
%ADD35C,.03204*%
%ADD34C,.07004*%
%ADD27C,.05204*%
%ADD28C,.04404*%
%ADD26C,.04604*%
%ADD33C,.07404*%
%ADD29C,.08504*%
%ADD36C,.08506*%
%ADD37C,.08606*%
%ADD31C,.07904*%
%ADD38C,.10306*%
%ADD40O,1.60381X.06402*%
%ADD32C,.23704*%
%ADD39C,.18206*%
%ADD30C,.13904*%
G75*
%LPD*%
G75*
G36*
G01X4600Y3200D02*
X3700Y4100D01*
Y211600D01*
X-500Y215800D01*
X-139900D01*
X-140600Y216500D01*
Y338800D01*
X-140100Y339300D01*
X-62600D01*
X-61000Y339700D01*
X-59800Y340200D01*
X-58300Y341200D01*
X-57000Y342700D01*
X-56200Y344400D01*
X-56000Y345500D01*
Y504100D01*
X-55300Y504800D01*
X-3400D01*
X-1500Y505100D01*
X700Y506400D01*
X744Y506455D01*
G02X1100Y506330I156J-125D01*
G01Y328400D01*
X15541Y313959D01*
G02X15530Y313384I-283J-282D01*
G03X18784Y310130I1570J-1684D01*
G02X19359Y310141I293J-272D01*
G01X50300Y279200D01*
Y277862D01*
X50272Y277815D01*
G03X52764Y274404I1985J-1166D01*
G01X52872Y274428D01*
X85002Y242298D01*
X85016Y242249D01*
G03X86585Y240680I2211J642D01*
G01X86634Y240666D01*
X86800Y240500D01*
X112000D01*
X115500Y244000D01*
X122900D01*
X126750Y247850D01*
X134852D01*
G02X135509Y247559I257J-307D01*
G03X140088Y247322I2300J88D01*
G01X140113Y247494D01*
X148734D01*
X150211Y246016D01*
G02X150038Y245349I-283J-283D01*
G03X152881Y242506I628J-2215D01*
G02X153548Y242679I384J-110D01*
G01X157574Y238653D01*
X157569Y238564D01*
G03X158805Y236464I2199J-120D01*
G02X158842Y235764I-174J-360D01*
G03X160967Y235874I1162J-1870D01*
G02X160930Y236574I174J360D01*
G03X159706Y240645I-1162J1870D01*
G01X159620Y240643D01*
X149916Y250346D01*
X145547D01*
G02X145160Y250848I0J400D01*
G03X145233Y251520I-2227J582D01*
G02X145633Y251936I400J16D01*
G01X167370D01*
X171491Y256057D01*
X171583Y256050D01*
G03X169467Y258166I179J2295D01*
G01X169474Y258074D01*
X166188Y254788D01*
X141050D01*
Y274150D01*
X144500Y277600D01*
Y278342D01*
X144503Y278360D01*
G03Y279206I-2262J423D01*
G01X144500Y279224D01*
Y280000D01*
X137300Y287200D01*
Y292800D01*
X70100Y360000D01*
X65868D01*
X52400Y373467D01*
Y387200D01*
X52900Y387700D01*
X55583D01*
X87235Y356048D01*
X87252D01*
X88700Y354600D01*
X193254D01*
X193312Y354500D01*
G03X197302I1995J1149D01*
G01X197360Y354600D01*
X236395D01*
X236455Y354535D01*
G03X239847I1696J1557D01*
G01X239907Y354600D01*
X273900D01*
X297700Y378400D01*
X490446D01*
G02X490729Y377717I0J-400D01*
G01X319738Y206726D01*
X114919D01*
X105819Y215826D01*
X84744D01*
X78307Y222263D01*
X78314Y222355D01*
G03X76198Y220239I-2295J179D01*
G01X76290Y220246D01*
X83562Y212974D01*
X104637D01*
X108982Y208629D01*
G02Y208063I-283J-283D01*
G03X109365Y204500I1628J-1627D01*
G02X109494Y203961I-216J-337D01*
G03X109205Y202460I1988J-1161D01*
G02X108810Y202002I-395J-58D01*
G01X86793D01*
G02X86474Y202643I0J400D01*
G03X82340Y204092I-1833J1393D01*
G02X81940Y203702I-400J10D01*
G01X72195D01*
X70094Y201601D01*
X70020Y201595D01*
G03X72495Y199120I180J-2295D01*
G01X72501Y199194D01*
X73605Y200298D01*
X81795D01*
X83495Y198598D01*
X117905D01*
X118805Y199498D01*
X119700D01*
G02X120100Y199084I0J-400D01*
G03X124700I2300J-84D01*
G02X125100Y199498I400J14D01*
G01X129405D01*
X130805Y200898D01*
X148115D01*
G02X148398Y200216I0J-400D01*
G01X129327Y181144D01*
G02X128678Y181265I-283J283D01*
G03X123945Y181317I-2378J-1056D01*
G01X123891Y181202D01*
X88088D01*
X81788Y174902D01*
X72048D01*
G02X71716Y175523I1J400D01*
G03X67884I-1916J1277D01*
G02X67552Y174902I-333J-221D01*
G01X60712D01*
X59739Y175874D01*
X59725Y175928D01*
G03X56572Y172775I-2525J-628D01*
G01X56626Y172761D01*
X58888Y170498D01*
X83612D01*
X89912Y176798D01*
X124009D01*
G02X124292Y176116I0J-400D01*
G01X123148Y174972D01*
Y174966D01*
X116709Y168526D01*
X87809D01*
X69248Y149966D01*
Y146808D01*
X69178Y146748D01*
G03X72172I1497J-1748D01*
G01X72102Y146808D01*
Y148784D01*
X74482Y151165D01*
G02X74824Y151023I142J-141D01*
G01X74823Y150658D01*
X74754Y150599D01*
G03X77746I1496J-1749D01*
G01X77676Y150659D01*
Y152025D01*
X88875Y163224D01*
X186261D01*
G02X186661Y162807I0J-400D01*
G03X191261I2300J-92D01*
G02X191661Y163224I400J17D01*
G01X350149D01*
X371793Y141580D01*
X371684Y141440D01*
G03X374992Y141770I1812J-1419D01*
G01X374922Y141830D01*
Y142485D01*
X351331Y166076D01*
X192293D01*
G02X191894Y166510I0J400D01*
G03X191314Y168237I-2294J190D01*
G01X191290Y168264D01*
X191237Y168399D01*
X191298Y168542D01*
X191325Y168570D01*
G03X191547Y171575I-1625J1631D01*
G01X191528Y171601D01*
X191487Y171721D01*
X191553Y171869D01*
X191583Y171897D01*
G03X188171Y172211I-1565J1689D01*
G01X188190Y172185D01*
X188231Y172065D01*
X188165Y171917D01*
X188135Y171889D01*
G03X187986Y168663I1565J-1689D01*
G01X188010Y168636D01*
X188063Y168501D01*
X188002Y168358D01*
X187975Y168330D01*
G03X187306Y166510I1625J-1630D01*
G02X186907Y166076I-399J-34D01*
G01X169457D01*
G02X169095Y166648I0J400D01*
G03X164935I-2080J985D01*
G02X164573Y166076I-362J-172D01*
G01X160783D01*
G02X160385Y166524I-1J400D01*
G03X155815I-2285J276D01*
G02X155417Y166076I-397J-48D01*
G01X119457Y166128D01*
G02X118977Y166759I-197J348D01*
G01X124096Y171879D01*
G02X124688Y171850I283J-283D01*
G03X128350Y175512I2012J1650D01*
G02X128321Y176104I254J309D01*
G01X133066Y180849D01*
G02X133741Y180486I283J-283D01*
G03X135773Y182518I2550J-518D01*
G02X135410Y183193I-80J392D01*
G01X151091Y198874D01*
X322691D01*
X395591Y271774D01*
X725491D01*
X725551Y271704D01*
G03Y274696I1749J1496D01*
G01X725491Y274626D01*
X396498D01*
G02X396216Y275309I1J400D01*
G01X507905Y386998D01*
X515490D01*
X515546Y386950D01*
G03X518613Y390381I1496J1749D01*
G02X518887Y391074I273J293D01*
G01X636126Y390809D01*
X636929Y391612D01*
X637021Y391605D01*
G03X634907Y394108I179J2295D01*
G01X634891Y393926D01*
X502609D01*
X490983Y382300D01*
X478000D01*
X477200Y383100D01*
Y389700D01*
X475400Y391500D01*
X471204D01*
G02X470921Y392183I0J400D01*
G01X505491Y426752D01*
X506498D01*
X506558Y426682D01*
G03Y429676I1748J1497D01*
G01X506498Y429606D01*
X504309D01*
X467230Y392527D01*
X399792D01*
G02X399509Y393209I0J400D01*
G01X492650Y486350D01*
X497806D01*
X497852Y486324D01*
G03X499418Y486059I1143J1998D01*
G01X499522Y486078D01*
X500700Y484900D01*
Y480000D01*
X499200Y478500D01*
Y476200D01*
X500600Y474800D01*
X504200D01*
X561000Y418000D01*
X628749D01*
X679575Y367174D01*
X727909D01*
X755912Y339171D01*
X755905Y339079D01*
G03X758021Y341195I2295J-179D01*
G01X757929Y341188D01*
X730627Y368491D01*
G02X730910Y369174I283J283D01*
G01X754891D01*
X754951Y369104D01*
G03Y372096I1749J1496D01*
G01X754891Y372026D01*
X681091D01*
X661481Y391637D01*
G02X661813Y392316I283J282D01*
G03X663849Y393104I287J2284D01*
G01X663909Y393174D01*
X755109D01*
X760612Y387671D01*
X760605Y387579D01*
G03X762721Y389695I2295J-179D01*
G01X762629Y389688D01*
X756291Y396026D01*
X663909D01*
X663849Y396096D01*
G03X659816Y394313I-1749J-1496D01*
G02X659137Y393981I-397J-49D01*
G01X634000Y419117D01*
Y424800D01*
X634873Y425674D01*
X698591D01*
X702129Y429212D01*
X702221Y429205D01*
G03X700690Y433041I179J2295D01*
G02X700083Y433056I-297J268D01*
G03X696005Y431421I-1783J-1456D01*
G01X696012Y431329D01*
X695159Y430476D01*
X636224D01*
X636200Y430500D01*
X563100D01*
X504200Y489400D01*
Y495500D01*
X504700Y496000D01*
X680163D01*
G02X680437Y495309I0J-400D01*
G03X683593I1578J-1676D01*
G02X683867Y496000I274J291D01*
G01X684200D01*
X685252Y497052D01*
X747370D01*
X747517Y497200D01*
X749300D01*
X762708Y510608D01*
X762766Y510621D01*
X762767D01*
G03X764524Y512378I-492J2249D01*
G01Y512379D01*
X764537Y512437D01*
X764600Y512500D01*
Y514200D01*
X758810Y519990D01*
X758817Y520083D01*
Y520084D01*
G03X757790Y522194I-2294J188D01*
G01X757700Y522253D01*
Y533187D01*
X757770Y533247D01*
G03Y536743I-1498J1748D01*
G01X757700Y536803D01*
Y538700D01*
X750000Y546400D01*
X712000D01*
X704516Y553884D01*
X704560Y554004D01*
G03X701604Y556960I-2160J796D01*
G01X701484Y556916D01*
X701200Y557200D01*
X672600D01*
X670200Y554800D01*
X650300D01*
X648700Y553200D01*
X642500D01*
X637200Y558500D01*
X568000D01*
X567900Y558400D01*
X530000D01*
X518209Y570191D01*
G02X518492Y570874I283J283D01*
G01X737791D01*
X741841Y574924D01*
X741955Y574890D01*
G03X740323Y577441I645J2210D01*
G01X740068Y577186D01*
G02X739432Y577281I-283J283D01*
G03X735924Y574433I-2032J-1081D01*
G02X735668Y573726I-256J-307D01*
G01X325609D01*
X325483Y573600D01*
X311500D01*
X305500Y567600D01*
X211100D01*
X192100Y548600D01*
X96700D01*
X75700Y527600D01*
Y516392D01*
G02X75040Y516088I-400J0D01*
G03X73323Y512048I-1498J-1748D01*
G02X73567Y511367I-38J-398D01*
G01X60300Y498100D01*
Y491000D01*
X59900Y490600D01*
X55300D01*
X54800Y491100D01*
Y505400D01*
X59400Y510000D01*
Y520679D01*
X338408Y799687D01*
Y799709D01*
X342600Y803900D01*
Y815930D01*
G02X343342Y816137I400J0D01*
G03X342988Y819793I3640J2198D01*
G01X342940Y819662D01*
X342600D01*
Y820000D01*
X338732Y823868D01*
G02X338840Y824510I283J282D01*
G03X334115Y825195I-1858J3825D01*
G02X333845Y824500I-270J-295D01*
G01X330119D01*
G02X329849Y825195I0J400D01*
G03X324115I-2867J3140D01*
G02X323845Y824500I-270J-295D01*
G01X320119D01*
G02X319849Y825195I0J400D01*
G03X314115I-2867J3140D01*
G02X313845Y824500I-270J-295D01*
G01X310119D01*
G02X309849Y825195I0J400D01*
G03X304115I-2867J3140D01*
G02X303845Y824500I-270J-295D01*
G01X300119D01*
G02X299849Y825195I0J400D01*
G03X294115I-2867J3140D01*
G02X293845Y824500I-270J-295D01*
G01X290119D01*
G02X289849Y825195I0J400D01*
G03X285953Y824209I-2867J3140D01*
G02X286139Y823539I-97J-388D01*
G01X284000Y821400D01*
Y821367D01*
X283943Y821309D01*
G03Y815361I3039J-2974D01*
G01X284000Y815303D01*
Y800837D01*
G02X283424Y800478I-400J0D01*
G03Y796342I-1011J-2068D01*
G02X284000Y795983I176J-359D01*
G01Y778900D01*
X102400Y597300D01*
X89900D01*
X87100Y594500D01*
Y578600D01*
X77900Y569400D01*
X70417D01*
X70380Y569416D01*
G03X68666I-857J-2029D01*
G01X68629Y569400D01*
X67600D01*
X67300Y569700D01*
Y571000D01*
X67700Y571400D01*
X68671D01*
X68704Y571388D01*
G03X70196I746J2072D01*
G01X70229Y571400D01*
X70800D01*
X71600Y572200D01*
Y572985D01*
X71604Y573005D01*
G03Y573915I-2154J455D01*
G01X71600Y573935D01*
Y577700D01*
X70700Y578600D01*
X70431D01*
X70388Y578622D01*
G03X68388I-1000J-1962D01*
G01X68345Y578600D01*
X60800D01*
X60300Y578100D01*
Y562200D01*
X60900Y561600D01*
X67300D01*
X67800Y562100D01*
X68852D01*
X68882Y562090D01*
G03X70032Y562037I673J2097D01*
G01X70139Y562061D01*
X70350Y561850D01*
Y561394D01*
X40756Y531800D01*
Y531255D01*
X40600Y531100D01*
X38878D01*
X38850Y531108D01*
G03X37550I-650J-2208D01*
G01X37522Y531100D01*
X33062D01*
Y544451D01*
X28802Y548712D01*
Y551052D01*
G02X29509Y551307I400J0D01*
G03Y555781I2695J2237D01*
G02X28802Y556036I-307J255D01*
G01Y621130D01*
G02X29509Y621385I400J0D01*
G03X31268Y626997I2695J2237D01*
G02X30878Y627665I-107J385D01*
G01X32011Y628798D01*
X44411D01*
X49402Y633788D01*
Y646012D01*
X49033Y646381D01*
X49019Y646406D01*
Y646407D01*
G03X45284Y646834I-2018J-1107D01*
G02X44611Y646961I-298J267D01*
G03X44547Y644217I-3469J-1292D01*
G01X44571Y644271D01*
X44755Y644395D01*
X44933Y644285D01*
X44958Y644236D01*
G03X44974Y644206I2040J1068D01*
G01X44998Y644161D01*
Y637878D01*
G02X44261Y637662I-400J0D01*
G03X37945Y633802I-3119J-1993D01*
G02X37600Y633200I-345J-202D01*
G01X30187D01*
X24398Y627412D01*
Y546888D01*
X28660Y542627D01*
Y541095D01*
G02X28057Y540751I-400J1D01*
G03Y534367I-1876J-3192D01*
G02X28660Y534023I203J-345D01*
G01Y531095D01*
G02X28057Y530751I-400J1D01*
G03Y524367I-1876J-3192D01*
G02X28660Y524023I203J-345D01*
G01Y521095D01*
G02X28057Y520751I-400J1D01*
G03X28274Y514505I-1876J-3192D01*
G02X28900Y514175I226J-330D01*
G01Y510900D01*
X32400Y507400D01*
Y496000D01*
X32300Y495900D01*
Y480200D01*
X26451Y474351D01*
G02X25894Y474343I-283J283D01*
G03X22640Y471089I-1579J-1675D01*
G02X22632Y470532I-291J-274D01*
G01X22216Y470116D01*
X22096Y470160D01*
G03X19140Y467204I-796J-2160D01*
G01X19184Y467084D01*
X11500Y459400D01*
X7100D01*
X3300Y463200D01*
Y550949D01*
G02X3999Y551215I400J0D01*
G03Y555873I2615J2329D01*
G02X3300Y556139I-299J266D01*
G01Y669059D01*
G02X3999Y669325I400J0D01*
G03Y673983I2615J2329D01*
G02X3300Y674249I-299J266D01*
G01Y783200D01*
X4300Y784200D01*
X77800D01*
X81900Y788300D01*
Y920100D01*
X83400Y921600D01*
X755400D01*
X756400Y920600D01*
Y818500D01*
X760500Y814400D01*
X771300D01*
X772500Y813200D01*
Y793300D01*
X771600Y792400D01*
X762800D01*
X759100Y788700D01*
Y782300D01*
X763100Y778300D01*
X771500D01*
X772300Y777500D01*
Y741800D01*
X771500Y741000D01*
X760600D01*
X756400Y736800D01*
Y661300D01*
X760700Y657000D01*
X771100D01*
X772800Y655300D01*
Y383900D01*
X772000Y383100D01*
X762100D01*
X759050Y380050D01*
Y372900D01*
X763025Y368925D01*
X771575D01*
X772800Y367700D01*
Y331700D01*
X772400Y331300D01*
X760500D01*
X756400Y327200D01*
Y4400D01*
X755200Y3200D01*
X4600D01*
G37*
G36*
G01X-23150Y447400D02*
X-25350Y449600D01*
Y504800D01*
X-3400D01*
X-1500Y505100D01*
X700Y506400D01*
X2300Y508400D01*
X3100Y510900D01*
X10800D01*
Y469000D01*
X13100Y466700D01*
Y461000D01*
X8187Y456087D01*
X8138Y456072D01*
G03X6580Y454514I650J-2208D01*
G01X6565Y454465D01*
X-500Y447400D01*
X-23150D01*
G37*
G36*
G01X98715Y474233D02*
X96315Y476633D01*
Y501715D01*
X117500Y522900D01*
X217231D01*
X217258Y522892D01*
G03X218540I641J2211D01*
G01X218567Y522900D01*
X225700D01*
X227100Y521500D01*
Y511600D01*
X228376Y510324D01*
X234276D01*
X234774Y509826D01*
Y503674D01*
X234259Y503159D01*
X219541D01*
X216500Y506200D01*
X127000D01*
X120141Y499341D01*
Y490900D01*
X119104Y489863D01*
X118964Y489980D01*
G03X117131Y487603I-960J-1155D01*
G01X117215Y487543D01*
Y479133D01*
X112315Y474233D01*
X103441D01*
X103381Y474305D01*
G03X101073I-1154J-961D01*
G01X101013Y474233D01*
X98715D01*
G37*
G36*
G01X109476Y427424D02*
X108057Y428843D01*
Y447457D01*
X110060Y449460D01*
X112460D01*
X120078Y457078D01*
G02X120729Y456951I283J-283D01*
G03X122697Y458919I1384J584D01*
G02X122570Y459570I156J368D01*
G01X126190Y463190D01*
Y466490D01*
X127500Y467800D01*
X129436D01*
X129466Y467790D01*
G03X131351Y468741I461J1430D01*
G01X131366Y468786D01*
X135652Y473072D01*
G02X136327Y472867I283J-283D01*
G03X138091Y474631I1474J290D01*
G02X137886Y475306I78J392D01*
G01X138235Y475655D01*
X138280Y475670D01*
G03X139225Y476615I-479J1424D01*
G01X139240Y476660D01*
X139589Y477009D01*
G02X140264Y476804I283J-283D01*
G03X142028Y478568I1474J290D01*
G02X141823Y479243I78J392D01*
G01X142172Y479592D01*
X142217Y479607D01*
G03X143162Y480552I-479J1424D01*
G01X143177Y480597D01*
X143526Y480946D01*
G02X144201Y480741I283J-283D01*
G03X145965Y482505I1474J290D01*
G02X145760Y483180I78J392D01*
G01X146109Y483529D01*
X146154Y483544D01*
G03X147099Y484489I-479J1424D01*
G01X147114Y484534D01*
X147504Y484924D01*
G02X148172Y484748I283J-283D01*
G03X150021Y486597I1448J401D01*
G02X149845Y487265I107J385D01*
G01X150046Y487466D01*
X150091Y487481D01*
G03X151036Y488426I-479J1424D01*
G01X151051Y488471D01*
X155831Y493251D01*
X159521D01*
G02X159921Y492849I0J-400D01*
G03X162925I1502J-7D01*
G02X163325Y493251I400J2D01*
G01X167395D01*
G02X167795Y492849I0J-400D01*
G03X170799I1502J-7D01*
G02X171199Y493251I400J2D01*
G01X176572D01*
X176588Y493068D01*
G03X179580I1496J130D01*
G01X179596Y493251D01*
X185637D01*
X188371Y490517D01*
Y485331D01*
X187182Y484142D01*
X175965D01*
G02X175570Y484604I0J400D01*
G03X175045Y485995I-1484J235D01*
G02X175127Y486663I256J308D01*
G03X173516Y486860I-652J1353D01*
G02X173434Y486192I-256J-308D01*
G03X173023Y483778I652J-1353D01*
G02Y483213I-283J-282D01*
G01X167385Y477575D01*
G02X166736Y477697I-283J283D01*
G03X163955Y476563I-1376J-603D01*
G02X163581Y476022I-374J-141D01*
G01X163202D01*
G02X162828Y476563I0J400D01*
G03X160605Y475835I-1405J531D01*
G02X160669Y475216I-218J-335D01*
G01X159693Y474240D01*
Y466171D01*
X155930Y462408D01*
X154243D01*
X154203Y462426D01*
G03X152963I-620J-1368D01*
G01X152923Y462408D01*
X146870D01*
X143017Y458555D01*
X142879Y458653D01*
G03X140784Y456558I-871J-1224D01*
G01X140882Y456420D01*
X140434Y455972D01*
Y454074D01*
X140400Y454024D01*
G03Y452354I1249J-835D01*
G01X140434Y452304D01*
Y450282D01*
X140411Y450238D01*
G03Y448832I1327J-703D01*
G01X140434Y448788D01*
Y446047D01*
X140425Y446018D01*
G03Y445148I1438J-435D01*
G01X140434Y445119D01*
Y444810D01*
X134638Y439015D01*
X134511Y439076D01*
G03X132508Y437073I-647J-1356D01*
G01X132569Y436946D01*
X130712Y435089D01*
Y435061D01*
X123076Y427424D01*
X114436D01*
X114415Y427429D01*
G03X113767I-324J-1467D01*
G01X113746Y427424D01*
X109476D01*
G37*
G36*
G01X236500Y518700D02*
X228600Y526600D01*
X219900D01*
X216500Y530000D01*
Y536500D01*
X226500Y546500D01*
X259300D01*
X271600Y534200D01*
Y522400D01*
X267900Y518700D01*
X244106D01*
X244070Y518714D01*
G03X242130I-970J-2414D01*
G01X242094Y518700D01*
X236500D01*
G37*
G36*
G01X269600Y471600D02*
X262900Y478300D01*
Y495300D01*
X302800Y535200D01*
X323300D01*
X327100Y531400D01*
Y523400D01*
X275300Y471600D01*
X269600D01*
G37*
G36*
G01X434926Y476783D02*
G03X436880Y478511I-515J2551D01*
G02X437398Y478759I379J-127D01*
G03X437541Y483689I902J2441D01*
G02X437037Y483973I-116J383D01*
G03X437031Y483996I-2521J-645D01*
G02X437418Y484498I387J102D01*
G01X456418D01*
X456445Y484489D01*
G03Y488909I646J2210D01*
G01X456418Y488900D01*
X410283D01*
X391338Y469956D01*
G02X390734Y470001I-283J283D01*
G03X387514Y466781I-1850J-1370D01*
G02X387559Y466177I-238J-321D01*
G01X386062Y464680D01*
X386037Y464666D01*
G03X389162Y461541I1106J-2019D01*
G01X389176Y461566D01*
X400817Y473208D01*
G02X401500Y472925I283J-283D01*
G01Y458200D01*
X379500Y436200D01*
X323900D01*
X323000Y437100D01*
Y441200D01*
X381300Y499500D01*
X445128D01*
G02X445419Y498825I0J-400D01*
G03X448761I1671J-1583D01*
G02X449052Y499500I291J275D01*
G01X457000D01*
X459200Y501700D01*
X480418D01*
G02X480802Y501186I1J-400D01*
G03X485214I2206J-657D01*
G02X485598Y501700I383J114D01*
G01X494800D01*
X495600Y500900D01*
Y494000D01*
X493600Y492000D01*
X485300D01*
X390300Y397000D01*
X297800D01*
X297000Y397800D01*
Y399900D01*
X321500Y424400D01*
X359800D01*
X362500Y421700D01*
X365997D01*
X366023Y421693D01*
G03X367415I696J2507D01*
G01X367441Y421700D01*
X385600D01*
X413500Y449600D01*
Y476600D01*
X412400Y477700D01*
X411299D01*
X411198Y477802D01*
X406377D01*
G02X406094Y478484I0J400D01*
G01X412107Y484498D01*
X431612D01*
G02X431999Y483996I0J-400D01*
G03X432531Y481650I2516J-663D01*
G02X432517Y481117I-305J-259D01*
G03X431820Y479109I1895J-1783D01*
G02X431500Y478683I-399J-34D01*
G03X434606Y476357I514J-2551D01*
G02X434926Y476783I399J34D01*
G37*
G36*
G01X318600Y426750D02*
X317900Y427450D01*
Y434400D01*
X318400Y434900D01*
X381300D01*
X403000Y456600D01*
Y474500D01*
X405100Y476600D01*
X410700D01*
X411800Y475500D01*
Y451400D01*
X387200Y426800D01*
X381965D01*
X381914Y426834D01*
G03X379002I-1456J-2156D01*
G01X378951Y426800D01*
X377180D01*
X377139Y426820D01*
G03X374891I-1124J-2347D01*
G01X374850Y426800D01*
X372532D01*
X372491Y426820D01*
G03X370243I-1124J-2347D01*
G01X370202Y426800D01*
X366821D01*
X366817D01*
G03X366621I-98J-2600D01*
G01X366617D01*
X326500D01*
X326450Y426750D01*
X318600D01*
G37*
%LPC*%
G75*
G36*
G01X53559Y85196D02*
G02X50241I-1659J-1596D01*
G03X49953Y85874I-288J278D01*
G01X46264D01*
X46230Y85716D01*
G02X44159Y88495I-2250J484D01*
G01X44251Y88488D01*
X44489Y88726D01*
X49311D01*
G03X49694Y89241I0J400D01*
G02X50142Y91386I2206J659D01*
G03X50127Y91919I-306J258D01*
G02X53855Y94536I1672J1582D01*
G01X53911Y94426D01*
X70391D01*
X71891Y92926D01*
X75595D01*
G03X75832Y93648I0J400D01*
G02X79219Y94394I1368J1852D01*
G03X79574Y93802I351J-192D01*
G02X80888Y89592I26J-2302D01*
G01X80800Y89533D01*
Y87602D01*
X80880Y87542D01*
G02X77205Y85879I-1380J-1842D01*
G01X77212Y85971D01*
X74809Y88374D01*
X70693D01*
G03X70294Y87940I0J-400D01*
G02X66716Y85839I-2294J-190D01*
G01X66665Y85874D01*
X53847D01*
G03X53559Y85196I0J-400D01*
G37*
G36*
G01X178432Y96543D02*
G02X175995Y96451I-1132J-2343D01*
G03X175968Y97157I-201J346D01*
G02X175922Y101820I1132J2343D01*
G03X175935Y102526I-181J356D01*
G02X178378Y102480I1265J2274D01*
G03X178365Y101774I181J-356D01*
G02X178405Y97249I-1265J-2274D01*
G03X178432Y96543I201J-346D01*
G37*
G36*
G01X83298Y191046D02*
G02X81649Y189619I502J-2246D01*
G03X81187Y190152I-374J142D01*
G02X82836Y191579I-502J2246D01*
G03X83298Y191046I374J-142D01*
G37*
G36*
G01X123722Y226378D02*
G02X123674Y224108I1978J-1177D01*
G03X122978Y224122I-352J-190D01*
G02X123026Y226392I-1978J1177D01*
G03X123722Y226378I352J190D01*
G37*
G36*
G01X183384Y253168D02*
G02X181546Y253422I-1207J-1960D01*
G03X181646Y254147I-110J385D01*
G02X183484Y253893I1207J1960D01*
G03X183384Y253168I110J-385D01*
G37*
G36*
G01X184699Y263631D02*
G02X182501Y263236I-743J-2179D01*
G03X182377Y263924I-253J310D01*
G02X184575Y264319I743J2179D01*
G03X184699Y263631I253J-310D01*
G37*
G36*
G01X184210Y273976D02*
G02X181921Y273957I-1128J-2007D01*
G03X181915Y274651I-202J345D01*
G02X184204Y274670I1128J2007D01*
G03X184210Y273976I202J-345D01*
G37*
G36*
G01X663609Y458578D02*
G02X660351Y458161I-1443J-1664D01*
G03X660317Y458425I-165J113D01*
G02X660524Y461912I1443J1664D01*
G03X660587Y462174I-112J165D01*
G02X660423Y462546I2016J1111D01*
G03X659760Y462699I-379J-128D01*
G02X660264Y465002I-1565J1549D01*
G03X660930Y464865I375J137D01*
G02X663809Y461323I1673J-1581D01*
G03X663735Y461064I105J-170D01*
G02X663575Y458842I-1975J-975D01*
G03X663609Y458578I165J-113D01*
G37*
G36*
G01X737426Y470286D02*
G02X736042Y471956I-2167J-388D01*
G03X736578Y472401I142J374D01*
G02X737962Y470731I2167J388D01*
G03X737426Y470286I-142J-374D01*
G37*
G36*
G01X746111Y742412D02*
G02X744657Y741298I557J-2233D01*
G03X744211Y741881I-349J195D01*
G02X741610Y745175I-558J2233D01*
G03X741284Y745758I-355J184D01*
G02X739408Y749111I169J2296D01*
G03X739023Y749693I-355J183D01*
G02X740895Y750932I-173J2296D01*
G03X741280Y750350I355J-183D01*
G02X743496Y746993I173J-2296D01*
G03X743822Y746410I355J-184D01*
G02X745665Y742995I-169J-2296D01*
G03X746111Y742412I349J-195D01*
G37*
G36*
G01X741596Y796237D02*
G02X739861Y797539I-2086J-973D01*
G03X740284Y798104I61J395D01*
G02X742294Y801378I2086J973D01*
G03X742653Y801926I-13J400D01*
G02X746611Y804189I2137J855D01*
G03X747322Y804368I316J245D01*
G02X747772Y802583I2271J-377D01*
G03X747061Y802404I-316J-245D01*
G02X744866Y800480I-2271J377D01*
G03X744507Y799932I13J-400D01*
G02X742019Y796802I-2137J-855D01*
G03X741596Y796237I-61J-395D01*
G37*
G36*
G01X682300Y803403D02*
G02X680269Y804680I-2061J-1025D01*
G03X680632Y805258I5J400D01*
G02X682538Y808580I2061J1025D01*
G03X682840Y809207I-27J399D01*
G02X684887Y808221I1892J1311D01*
G03X684585Y807594I27J-399D01*
G02X682663Y803981I-1892J-1311D01*
G03X682300Y803403I-5J-400D01*
G37*
G36*
G01X300673Y44190D02*
G03Y43510I211J-340D01*
G02X297927I-1373J-2210D01*
G03Y44190I-211J340D01*
G02X300673I1373J2210D01*
G37*
G36*
G01X284916Y45542D02*
G03X284296I-310J-253D01*
G02Y48836I-2014J1647D01*
G03X284916I310J253D01*
G02X288775Y49024I2014J-1647D01*
G03X289367Y49051I284J282D01*
G02X289528Y45559I2006J-1657D01*
G03X288936Y45532I-284J-282D01*
G02X284916Y45542I-2006J1657D01*
G37*
G36*
G01X242758Y83394D02*
G03X242754Y82832I283J-283D01*
G02X239475Y82859I-1653J-1602D01*
G03X239479Y83421I-283J283D01*
G02X240149Y87104I1653J1602D01*
G03X240349Y87614I-171J361D01*
G02X243471Y86385I2138J852D01*
G03X243271Y85875I171J-361D01*
G02X242758Y83394I-2139J-851D01*
G37*
G36*
G01X203352Y104689D02*
G03X202817Y104676I-260J-304D01*
G02X202734Y108099I-1580J1674D01*
G03X203269Y108112I260J304D01*
G02X203352Y104689I1580J-1674D01*
G37*
G36*
G01X64924Y108705D02*
G03X65545Y108690I317J244D01*
G02X65476Y105795I1755J-1490D01*
G03X64855Y105810I-317J-244D01*
G02X64924Y108705I-1755J1490D01*
G37*
G36*
G01X86743Y109304D02*
G03X87335Y109289I303J261D01*
G02X87257Y106196I1665J-1589D01*
G03X86665Y106211I-303J-261D01*
G02X86743Y109304I-1665J1589D01*
G37*
G36*
G01X87036Y122303D02*
G03X87650Y122295I310J252D01*
G02X87614Y119347I1750J-1496D01*
G03X87000Y119355I-310J-252D01*
G02X83503Y119350I-1751J1495D01*
G03X82897I-303J-260D01*
G02Y122350I-1747J1500D01*
G03X83503I303J260D01*
G02X87036Y122303I1747J-1500D01*
G37*
G36*
G01X207061Y127739D02*
G03X206741Y127259I71J-394D01*
G02X201663Y127276I-2541J-560D01*
G03X201356Y127755I-390J88D01*
G02X203937Y131919I544J2545D01*
G03X204563I313J249D01*
G02X207061Y127739I2037J-1619D01*
G37*
G36*
G01X83449Y149276D02*
G02X87977Y153804I2264J2264D01*
G01X92554Y149226D01*
X165601D01*
X167390Y147438D01*
G03X168062Y147629I283J283D01*
G02X172218Y145823I2240J-529D01*
G03X172550Y145202I333J-221D01*
G01X246510D01*
X253964Y137748D01*
G02X249436Y133220I-2264J-2264D01*
G01X243858Y138798D01*
X166974D01*
X162949Y142824D01*
X162428D01*
Y142584D01*
X162443Y142548D01*
G02X158098Y142313I-2132J-868D01*
G03X157713Y142824I-385J111D01*
G01X89902D01*
X87803Y144923D01*
G03X87132Y144737I-283J-283D01*
G02X84337Y147532I-2232J563D01*
G03X84523Y148203I-97J388D01*
G01X83449Y149276D01*
G37*
G36*
G01X221530Y175821D02*
G03X222182Y175768I345J203D01*
G02X221966Y173122I1766J-1476D01*
G03X221314Y173175I-345J-203D01*
G02X221530Y175821I-1766J1476D01*
G37*
G36*
G01X174591Y180333D02*
G03X175249Y180306I338J214D01*
G02X175141Y177691I1838J-1386D01*
G03X174483Y177718I-338J-214D01*
G02X174591Y180333I-1838J1386D01*
G37*
G36*
G01X28416Y188882D02*
G03X28164Y188319I107J-386D01*
G02X25484Y189518I-2064J-1019D01*
G03X25736Y190081I-107J386D01*
G02X28416Y188882I2064J1019D01*
G37*
G36*
G01X221432Y212733D02*
G03X221705Y212710I149J134D01*
G02X221414Y209366I1424J-1809D01*
G03X221141Y209389I-149J-134D01*
G02X221432Y212733I-1424J1809D01*
G37*
G36*
G01X135915Y219955D02*
G03X135862Y219302I202J-345D01*
G02X132424Y215398I-1663J-2001D01*
G03X131864Y215385I-273J-292D01*
G02X131776Y219102I-1864J1815D01*
G03X132336Y219115I273J292D01*
G02X132885Y219545I1864J-1815D01*
G03X132938Y220198I-202J345D01*
G02X135915Y219955I1662J2002D01*
G37*
G36*
G01X172905Y234546D02*
G03X173477Y234525I296J269D01*
G02X173359Y231311I1587J-1667D01*
G03X172787Y231332I-296J-269D01*
G02X172905Y234546I-1587J1667D01*
G37*
G36*
G01X187349Y239336D02*
G03X187313Y238803I279J-287D01*
G02X183893Y239030I-1812J-1420D01*
G03X183929Y239563I-279J287D01*
G02X184376Y242837I1811J1420D01*
G03X184350Y243500I-237J323D01*
G02X186927Y243602I1213J1956D01*
G03X186953Y242939I237J-323D01*
G02X187349Y239336I-1213J-1957D01*
G37*
G36*
G01X169520Y241394D02*
G03X169509Y241123I141J-141D01*
G02X166134Y241256I-1749J-1497D01*
G03X166145Y241527I-141J141D01*
G02X166416Y244789I1749J1497D01*
G03X166451Y245059I-128J154D01*
G02X169802Y244632I1873J1338D01*
G03X169767Y244362I128J-154D01*
G02X169520Y241394I-1873J-1338D01*
G37*
G36*
G01X58124Y253755D02*
G03X57475Y253764I-328J-229D01*
G02X57509Y256454I-1851J1369D01*
G03X58158Y256445I328J229D01*
G02X58124Y253755I1851J-1369D01*
G37*
G36*
G01X197661Y258546D02*
G03X197714Y258279I170J-105D01*
G02X194065Y256508I-1349J-1865D01*
G03X193461Y256869I-400J17D01*
G02X193438Y260839I-1177J1978D01*
G03X193711Y260911I100J173D01*
G02X197661Y258546I1987J-1162D01*
G37*
G36*
G01X57812Y264827D02*
G03X58436Y264769I335J218D01*
G02X58173Y261923I1666J-1589D01*
G03X57549Y261981I-335J-218D01*
G02X57812Y264827I-1666J1589D01*
G37*
G36*
G01X189308Y283618D02*
G03X189137Y283069I180J-357D01*
G02X185089Y280876I-2019J-1106D01*
G03X184576Y281053I-352J-189D01*
G02X182732Y285272I-922J2109D01*
G03X182938Y285801I-160J367D01*
G02X182875Y287509I2104J933D01*
G03X182768Y287759I-188J67D01*
G02X185874Y289086I938J2102D01*
G03X185981Y288836I188J-67D01*
G02X187055Y287851I-939J-2102D01*
G03X187313Y287766I175J97D01*
G02X189308Y283618I960J-2092D01*
G37*
G36*
G01X165209Y292371D02*
G03X164630Y292437I-321J-239D01*
G02X164984Y295574I-1488J1756D01*
G03X165563Y295508I321J239D01*
G02X165209Y292371I1488J-1756D01*
G37*
G36*
G01X535376Y409622D02*
X501316D01*
X501260Y409575D01*
G02Y413073I-1496J1749D01*
G01X501316Y413026D01*
X535376D01*
X535432Y413073D01*
G02Y409575I1496J-1749D01*
G01X535376Y409622D01*
G37*
G36*
G01X708059Y447750D02*
X683937D01*
X683891Y447724D01*
G02X681668Y451756I-1117J2013D01*
G01X681693Y451770D01*
X682076Y452152D01*
X708059D01*
G02Y447750I0J-2201D01*
G37*
G36*
G01X736855Y455680D02*
G03X736851Y455413I147J-136D01*
G02X733567Y455454I-1660J-1446D01*
G03X733571Y455721I-147J136D01*
G02X736855Y455680I1660J1446D01*
G37*
G36*
G01X669960Y456715D02*
G03X670468Y456443I385J109D01*
G02X669049Y453672I677J-2095D01*
G03X668532Y453926I-381J-122D01*
G02X669960Y456715I-787J2163D01*
G37*
G36*
G01X683153Y478149D02*
X683178Y478163D01*
X687334Y482318D01*
X705284D01*
X709902Y477701D01*
Y477173D01*
X709910Y477146D01*
G02X705492Y475849I-2210J-646D01*
G01X705477Y475898D01*
X703460Y477916D01*
X689158D01*
X686725Y475483D01*
G03X687008Y474800I283J-283D01*
G01X689800D01*
X690100Y474500D01*
Y455700D01*
X689600Y455200D01*
X685900D01*
X685600Y455500D01*
Y473597D01*
G03X685061Y473972I-400J0D01*
G02X683153Y478149I-803J2158D01*
G37*
G36*
G01X653038Y472491D02*
G03X653247Y472298I200J7D01*
G02X651150Y470028I104J-2200D01*
G03X650941Y470221I-200J-7D01*
G02X649053Y471130I-104J2200D01*
G03X648432Y471162I-323J-235D01*
G02X644995Y473904I-1639J1471D01*
G03X644950Y474181I-163J116D01*
G02X644606Y477430I1296J1780D01*
G03Y477697I-149J134D01*
G02X647891Y477692I1645J1464D01*
G03Y477425I149J-134D01*
G02X648045Y474691I-1645J-1464D01*
G03X648090Y474414I163J-116D01*
G02X648578Y473925I-1295J-1781D01*
G03X649199Y473893I323J235D01*
G02X653038Y472491I1638J-1472D01*
G37*
G36*
G01X748487Y474922D02*
G03Y474656I150J-133D01*
G02X745203I-1642J-1467D01*
G03Y474922I-150J133D01*
G02X744697Y475905I1642J1467D01*
G03X744186Y476198I-390J-88D01*
G02X745668Y478781I-666J2099D01*
G03X746179Y478488I390J88D01*
G02X748487Y474922I666J-2099D01*
G37*
G36*
G01X744548Y547914D02*
G03X744277Y547896I-126J-155D01*
G02X744059Y551267I-1670J1585D01*
G03X744330Y551285I126J155D01*
G02X744548Y547914I1670J-1585D01*
G37*
G36*
G01X699867Y558483D02*
G03X699305Y558453I-266J-299D01*
G02X699133Y561717I-1705J1547D01*
G03X699695Y561747I266J299D01*
G02X699867Y558483I1705J-1547D01*
G37*
G36*
G01X729926Y757239D02*
Y603091D01*
X766125Y566892D01*
X766215Y566898D01*
G02X764066Y564814I143J-2298D01*
G01X764075Y564908D01*
X761195Y567788D01*
G03X760540Y567652I-283J-283D01*
G02X756105Y568679I-2140J848D01*
G01X756112Y568771D01*
X741909Y582974D01*
X729509D01*
X729449Y582904D01*
G02Y585896I-1749J1496D01*
G01X729509Y585826D01*
X742190D01*
G03X742473Y586509I0J400D01*
G01X727074Y601909D01*
Y647775D01*
G03X726584Y648164I-400J-1D01*
G02Y653236I-584J2536D01*
G03X727074Y653625I90J390D01*
G01Y766191D01*
X733464Y772582D01*
Y822581D01*
G03X732782Y822864I-400J0D01*
G01X687226Y777308D01*
Y772703D01*
X687295Y772643D01*
G02X685620Y768599I-1496J-1749D01*
G01X685528Y768606D01*
X671526Y754604D01*
Y731987D01*
X671275Y731736D01*
X671282Y731644D01*
G02X668515Y733718I-2295J-179D01*
G01X668674Y733751D01*
Y737184D01*
G03X668230Y737581I-400J-1D01*
G02Y742159I-248J2289D01*
G03X668674Y742556I44J398D01*
G01Y755786D01*
X683511Y770623D01*
X683504Y770715D01*
G02X684303Y772643I2295J179D01*
G01X684372Y772703D01*
Y778490D01*
X729200Y823317D01*
Y824600D01*
X728000Y825800D01*
X724652D01*
X724604Y825669D01*
G02X720446Y827608I-2161J794D01*
G03X720337Y828129I-347J199D01*
G02X721615Y832281I1367J1852D01*
G03X722000Y832681I-15J400D01*
G01Y833422D01*
X721960Y833475D01*
G02Y836239I1841J1382D01*
G01X722000Y836292D01*
Y839228D01*
X721983Y839266D01*
G02X724290Y842481I2110J921D01*
G03X724504Y842648I17J199D01*
G02X728525Y843773I2272J-371D01*
G01X728585Y843704D01*
X730411D01*
X736318Y837797D01*
Y771400D01*
X729926Y765009D01*
Y762489D01*
G03X730421Y762100I400J0D01*
G02Y757628I546J-2236D01*
G03X729926Y757239I-95J-389D01*
G37*
G36*
G01X65800Y589200D02*
X63700Y587100D01*
X61000D01*
X60100Y588000D01*
Y611300D01*
X60300Y611500D01*
X66100D01*
X68400Y613800D01*
X70700D01*
X72000Y612500D01*
Y607000D01*
X70700Y605700D01*
X68500D01*
X68100Y605300D01*
Y603900D01*
X68200Y603800D01*
X70900D01*
X71800Y602900D01*
Y601593D01*
Y601591D01*
G02Y601463I-2201J-64D01*
G01Y601461D01*
Y596800D01*
X71000Y596000D01*
X70002D01*
X69984Y595996D01*
G02X69154I-415J2163D01*
G01X69136Y596000D01*
X68700D01*
X68400Y595700D01*
Y594200D01*
X68700Y593900D01*
X70700D01*
X72000Y592600D01*
Y590300D01*
X70900Y589200D01*
X69918D01*
X69907Y589199D01*
G02X69415I-246J2188D01*
G01X69404Y589200D01*
X65800D01*
G37*
G36*
G01X71700Y679900D02*
X70600Y678800D01*
X61400D01*
X60900Y679300D01*
Y695900D01*
X61100Y696100D01*
X67600D01*
X68100Y696600D01*
X69326D01*
X69332D01*
G02X69616I142J-2197D01*
G01X69622D01*
X70700D01*
X71800Y695500D01*
Y690100D01*
X70500Y688800D01*
X68200D01*
X67800Y688400D01*
Y687000D01*
X68200Y686600D01*
X70500D01*
X71700Y685400D01*
Y679900D01*
G37*
G36*
G01X89169Y710502D02*
G03X89153Y710773I-155J127D01*
G02X92524Y710973I1593J1662D01*
G03X92540Y710702I155J-127D01*
G02X92596Y707434I-1593J-1662D01*
G03X92604Y706868I287J-279D01*
G02X92717Y703677I-1601J-1654D01*
G03X92727Y703399I148J-134D01*
G02X89416Y703278I-1597J-1658D01*
G03X89406Y703556I-148J134D01*
G02X89354Y706820I1597J1658D01*
G03X89346Y707386I-287J279D01*
G02X89169Y710502I1601J1654D01*
G37*
G36*
G01X221962Y739354D02*
G03X221358Y739342I-297J-268D01*
G02X221299Y742358I-1768J1474D01*
G03X221903Y742370I297J268D01*
G02X221962Y739354I1768J-1474D01*
G37*
G36*
G01X725628Y772793D02*
G03X725721Y772265I339J-212D01*
G02X722355Y771673I-1416J-1815D01*
G03X722262Y772201I-339J212D01*
G02X724829Y776010I1415J1816D01*
G03X725391Y776187I200J346D01*
G02X726326Y773218I2086J-975D01*
G03X725764Y773041I-200J-346D01*
G02X725628Y772793I-2083J981D01*
G37*
G36*
G01X727331Y780700D02*
G03X726947Y780190I0J-400D01*
G02X723853Y781686I-2214J-631D01*
G03X723872Y782417I-153J370D01*
G02X723744Y786511I987J2080D01*
G03X723800Y787173I-194J350D01*
G02X726564Y790852I1440J1796D01*
G03X727193Y791214I230J327D01*
G02X731067Y789743I2293J202D01*
G03X731142Y789106I275J-291D01*
G02X731048Y785071I-1154J-1992D01*
G03X731054Y784358I184J-355D01*
G02X728426Y780644I-1026J-2061D01*
G01X728368Y780700D01*
X727331D01*
G37*
G36*
G01X669098Y783949D02*
G03X668600Y783743I-136J-376D01*
G02X667304Y786885I-2084J979D01*
G03X667802Y787091I136J376D01*
G02X669098Y783949I2084J-979D01*
G37*
G36*
G01X237445Y793165D02*
G03X237178Y792578I82J-392D01*
G02X234697Y793708I-2009J-1123D01*
G03X234964Y794295I-82J392D01*
G02X237445Y793165I2009J1123D01*
G37*
G36*
G01X747711Y794659D02*
G03X747352Y794104I10J-400D01*
G02X745178Y795512I-2122J-893D01*
G03X745537Y796067I-10J400D01*
G02X747711Y794659I2122J893D01*
G37*
G36*
G01X348952Y794966D02*
G03X348323I-314J-247D01*
G02Y797804I-1813J1419D01*
G03X348952I314J247D01*
G02Y794966I1813J-1419D01*
G37*
G36*
G01X747167Y811263D02*
G03X747474Y811798I-67J394D01*
G02X750018Y810339I2155J810D01*
G03X749711Y809804I67J-394D01*
G02X747167Y811263I-2155J-810D01*
G37*
G36*
G01X157400Y812700D02*
X157200Y812500D01*
X150700D01*
X150500Y812700D01*
Y819100D01*
X150800Y819400D01*
X156500D01*
X156800Y819700D01*
Y821700D01*
X158000Y822900D01*
X158889D01*
X158900Y822901D01*
G02X159374I237J-2189D01*
G01X159385Y822900D01*
X160200D01*
X161900Y821200D01*
Y816500D01*
X160600Y815200D01*
X157700D01*
X157400Y814900D01*
Y812700D01*
G37*
G36*
G01X162000Y828000D02*
X160900Y826900D01*
X158400D01*
X157900Y827400D01*
X149300D01*
X149100Y827600D01*
Y842400D01*
X149200Y842500D01*
X156700D01*
X158700Y844500D01*
X160600D01*
X161800Y843300D01*
Y838100D01*
X160400Y836700D01*
X157800D01*
X157400Y836300D01*
Y834900D01*
X157700Y834600D01*
X159078D01*
X159104Y834607D01*
G02X160272I584J-2123D01*
G01X160298Y834600D01*
X160800D01*
X162000Y833400D01*
Y828000D01*
G37*
G36*
G01X678631Y844059D02*
G03X678901Y844520I-122J381D01*
G02X679656Y846728I2255J462D01*
G03X679687Y846998I-130J152D01*
G02X681323Y850653I1855J1363D01*
G03X681645Y851226I-38J398D01*
G02X683934Y849941I2070J1007D01*
G03X683612Y849368I38J-398D01*
G02X683042Y846615I-2070J-1007D01*
G03X683011Y846345I130J-152D01*
G02X681857Y842789I-1855J-1363D01*
G03X681587Y842328I122J-381D01*
G02X678631Y844059I-2255J-462D01*
G37*
G36*
G01X717305Y28346D02*
X716791Y28322D01*
X716279D01*
X715765Y28346D01*
X715259Y28393D01*
X714746Y28462D01*
X714232Y28558D01*
X713729Y28681D01*
X713244Y28820D01*
X712757Y28984D01*
X712278Y29171D01*
X711807Y29380D01*
X711350Y29608D01*
X710898Y29861D01*
X710457Y30137D01*
X710040Y30427D01*
X709626Y30740D01*
X709237Y31071D01*
X708859Y31414D01*
X708495Y31784D01*
X708148Y32166D01*
X707824Y32566D01*
X707517Y32979D01*
X707231Y33405D01*
X706964Y33841D01*
X706717Y34291D01*
X706486Y34761D01*
X706287Y35237D01*
X706111Y35702D01*
X705945Y36197D01*
X705809Y36702D01*
X705698Y37205D01*
X705612Y37698D01*
X705541Y38207D01*
X705500Y38730D01*
X705482Y39241D01*
X705488Y39754D01*
X705518Y40268D01*
X705571Y40784D01*
X705653Y41293D01*
X705750Y41786D01*
X705875Y42297D01*
X706028Y42792D01*
X706195Y43269D01*
X706386Y43743D01*
X706599Y44217D01*
X706843Y44680D01*
X707095Y45116D01*
X707369Y45547D01*
X707670Y45972D01*
X707983Y46373D01*
X708318Y46768D01*
X708677Y47145D01*
X709043Y47499D01*
X709431Y47839D01*
X709837Y48163D01*
X710247Y48457D01*
X710670Y48741D01*
X711123Y49009D01*
X711575Y49246D01*
X712040Y49471D01*
X712512Y49663D01*
X712992Y49842D01*
X713492Y49996D01*
X713989Y50125D01*
X714485Y50228D01*
X714992Y50316D01*
X715508Y50376D01*
X716023Y50411D01*
X716535Y50423D01*
X717047Y50411D01*
X717562Y50376D01*
X718078Y50316D01*
X718585Y50228D01*
X719081Y50125D01*
X719578Y49996D01*
X720078Y49842D01*
X720558Y49663D01*
X721030Y49471D01*
X721495Y49246D01*
X721947Y49009D01*
X722400Y48741D01*
X722823Y48457D01*
X723233Y48163D01*
X723639Y47839D01*
X724027Y47499D01*
X724393Y47145D01*
X724752Y46768D01*
X725087Y46373D01*
X725400Y45972D01*
X725701Y45547D01*
X725975Y45116D01*
X726227Y44680D01*
X726471Y44217D01*
X726684Y43743D01*
X726875Y43269D01*
X727042Y42792D01*
X727195Y42297D01*
X727320Y41786D01*
X727417Y41293D01*
X727499Y40784D01*
X727552Y40268D01*
X727582Y39754D01*
X727588Y39241D01*
X727570Y38730D01*
X727529Y38207D01*
X727458Y37698D01*
X727372Y37205D01*
X727261Y36702D01*
X727125Y36197D01*
X726959Y35702D01*
X726783Y35237D01*
X726584Y34761D01*
X726353Y34291D01*
X726106Y33841D01*
X725839Y33405D01*
X725553Y32979D01*
X725246Y32566D01*
X724922Y32166D01*
X724575Y31784D01*
X724211Y31414D01*
X723833Y31071D01*
X723444Y30740D01*
X723030Y30427D01*
X722613Y30137D01*
X722172Y29861D01*
X721720Y29608D01*
X721263Y29380D01*
X720792Y29171D01*
X720313Y28984D01*
X719826Y28820D01*
X719341Y28681D01*
X718838Y28558D01*
X718324Y28462D01*
X717811Y28393D01*
X717305Y28346D01*
G37*
G36*
G01X704000Y474400D02*
Y455600D01*
X703700Y455300D01*
X700000D01*
X699800Y455500D01*
Y474600D01*
X699900Y474700D01*
X703700D01*
X704000Y474400D01*
G37*
G36*
G01X58800Y711700D02*
X60100Y713000D01*
Y730200D01*
X60200Y730300D01*
X66400D01*
X67700Y731600D01*
X70900D01*
X71900Y730600D01*
Y725000D01*
X70800Y723900D01*
X67700D01*
X67300Y723500D01*
Y721100D01*
X67800Y720600D01*
X70800D01*
X71800Y719600D01*
Y713800D01*
X70900Y712900D01*
X68500D01*
X68100Y712500D01*
Y706000D01*
X66600Y704500D01*
X59700D01*
X58800Y705400D01*
Y711700D01*
G37*
G36*
G01X150000Y848500D02*
X149800Y848700D01*
Y855200D01*
X150000Y855400D01*
X156300D01*
X157800Y853900D01*
X160800D01*
X162100Y852600D01*
Y847600D01*
X160600Y846100D01*
X158400D01*
X156000Y848500D01*
X150000D01*
G37*
G36*
G01X245885Y532200D02*
G03X245500Y531785I15J-400D01*
G02X241132Y530688I-2300J-85D01*
G01X241078Y530800D01*
X239399D01*
X239342Y530698D01*
G02X235363Y533014I-2006J1130D01*
G03X235210Y533573I-343J207D01*
G02X234811Y537356I1090J2028D01*
G03X234870Y537903I-259J305D01*
G02X238660Y540508I1830J1397D01*
G03X239340I340J210D01*
G02X243460Y538504I1960J-1207D01*
G01X243416Y538384D01*
X245103Y536697D01*
X245214Y536726D01*
G02X245885Y532200I587J-2226D01*
G37*
G36*
G01X273442Y495003D02*
G03X272907Y494746I-151J-370D01*
G02X271573Y497530I-2207J654D01*
G03X272108Y497787I151J370D01*
G02X273442Y495003I2207J-654D01*
G37*
G36*
G01X418479Y469152D02*
G03X419069Y469077I329J228D01*
G02X418684Y466023I1506J-1741D01*
G03X418094Y466098I-329J-228D01*
G02X418479Y469152I-1506J1741D01*
G37*
G36*
G01X384195Y469386D02*
G03Y468780I260J-303D01*
G02X381195I-1500J-1747D01*
G03Y469386I-260J303D01*
G02X384195I1500J1747D01*
G37*
G36*
G01X369383Y414999D02*
G03X368764Y414962I-294J-271D01*
G02X368571Y418242I-2111J1521D01*
G03X369190Y418279I294J271D01*
G02X373315Y418404I2111J-1522D01*
G03X373935I310J253D01*
G02X377794Y418592I2014J-1647D01*
G03X378386Y418619I284J282D01*
G02X378547Y415127I2006J-1657D01*
G03X377955Y415100I-284J-282D01*
G02X373935Y415110I-2006J1657D01*
G03X373315I-310J-253D01*
G02X369383Y414999I-2014J1647D01*
G37*
G36*
G01X369947Y406327D02*
G03X369328Y406290I-294J-271D01*
G02X369135Y409570I-2111J1521D01*
G03X369754Y409607I294J271D01*
G02X373879Y409732I2111J-1522D01*
G03X374499I310J253D01*
G02X378358Y409920I2014J-1647D01*
G03X378950Y409947I284J282D01*
G02X379111Y406455I2006J-1657D01*
G03X378519Y406428I-284J-282D01*
G02X374499Y406438I-2006J1657D01*
G03X373879I-310J-253D01*
G02X369947Y406327I-2014J1647D01*
G37*
G54D41*
X98427Y484968D03*
Y481031D03*
X102364D03*
Y484968D03*
X106301D03*
Y481031D03*
X114175Y484968D03*
Y481031D03*
X110238Y477094D03*
Y481031D03*
Y484968D03*
Y488905D03*
X102308Y488978D03*
X133864Y445598D03*
X137801D03*
Y453472D03*
X149612Y477094D03*
X117951Y437592D03*
X114175Y445598D03*
X110263Y441683D03*
X118189Y445711D03*
X125990Y445598D03*
X110238Y437720D03*
X125990D03*
X149594Y480923D03*
X149576Y465497D03*
X130080Y457372D03*
X141827Y461346D03*
X149563Y469220D03*
X145675Y473157D03*
Y465283D03*
X129927D03*
X137801Y461346D03*
Y457409D03*
X122053Y445598D03*
X129927D03*
X118134Y449362D03*
X110238Y445598D03*
X122053Y437720D03*
X114175D03*
X129927D03*
X137801Y449535D03*
X145675Y469220D03*
X137801D03*
X133864Y465283D03*
X129963Y461283D03*
X122158Y453388D03*
X177763Y486293D03*
X157411Y469344D03*
X153690Y469111D03*
X161423Y484968D03*
Y481031D03*
X157486Y473157D03*
X153549Y477094D03*
Y473157D03*
X165353Y480812D03*
X157508Y480990D03*
X157486Y484968D03*
X153601Y480894D03*
X153586Y485118D03*
X157486Y488905D03*
X165360D03*
G54D35*
X60800Y505200D03*
X61776Y367194D03*
G54D34*
X32204Y741732D03*
X18425D03*
X32204Y671654D03*
X18425D03*
Y623622D03*
Y553544D03*
X10551Y741732D03*
Y623622D03*
G54D27*
X745413Y854763D03*
X740000Y650600D03*
X733000D03*
X720000Y650800D03*
X711500Y438300D03*
X321300Y43200D03*
X351800Y42200D03*
X360500Y42600D03*
X330000Y42800D03*
X329900Y37100D03*
X321300D03*
X360500Y36700D03*
X351800Y36300D03*
X191500Y88500D03*
X183700Y78100D03*
X177500Y77900D03*
X177400Y71400D03*
X184500Y71200D03*
X191000Y71300D03*
X201200Y65600D03*
X190700Y77800D03*
X184700Y88500D03*
X177300D03*
X201500Y72300D03*
X209000D03*
X154500Y90000D03*
X158000Y79600D03*
X165200Y79500D03*
X163300Y95900D03*
X163500Y105500D03*
X151800Y72400D03*
X184700Y63100D03*
X200700Y58300D03*
X192000Y55900D03*
X208900Y58600D03*
X185100Y55900D03*
X200700Y51700D03*
X209200Y65100D03*
X191700Y63300D03*
X209100Y51700D03*
X136100Y173800D03*
X147500Y90200D03*
X142167Y106366D03*
X142101Y98650D03*
X111100Y75500D03*
X100000Y75600D03*
X121700Y75300D03*
X85300Y70200D03*
X87900Y47800D03*
X90900Y42400D03*
X80400Y47800D03*
X50500Y67700D03*
X70500Y72000D03*
X60800Y72500D03*
X45700Y61000D03*
X65500Y60800D03*
X75500D03*
X45900Y50000D03*
X65700Y49800D03*
X50800Y39500D03*
X70700Y45800D03*
X55800Y61300D03*
X59900Y40600D03*
G54D28*
X713845Y447289D03*
X726589Y460909D03*
X721445Y455789D03*
X731751Y464398D03*
X717993Y451389D03*
X675745Y448189D03*
X682915Y467823D03*
G54D26*
X733796Y854172D03*
X718263Y863827D03*
X721243Y850725D03*
X729250Y850000D03*
X725407Y794540D03*
X742663Y788885D03*
X734450Y755929D03*
X757600Y639700D03*
X717879Y564572D03*
X763000Y490800D03*
X729700Y551500D03*
X722687Y120650D03*
X678351Y854383D03*
X710727Y862002D03*
X690211Y827401D03*
X646342Y826469D03*
X686308Y834802D03*
X679630Y795856D03*
X676727Y790555D03*
X678755Y784815D03*
X680480Y773302D03*
X691075Y820814D03*
X663575Y742289D03*
X681402Y757754D03*
X689945Y758289D03*
X643100Y589900D03*
X669200Y559600D03*
X656817Y567131D03*
X644600Y556700D03*
X707890Y467821D03*
X688615Y485133D03*
X702000Y485700D03*
X523200Y399400D03*
X506100Y380000D03*
X500295Y401715D03*
X361814Y796557D03*
X365131Y135484D03*
X381025Y120650D03*
Y73748D03*
X362793Y126096D03*
Y77815D03*
X240130Y789012D03*
X271970Y798668D03*
X228021Y787335D03*
X223596Y782163D03*
X223129Y764830D03*
X281183Y592936D03*
X224664Y293860D03*
X231350Y222067D03*
X256928Y69301D03*
X261830Y81230D03*
X251687Y98033D03*
X254498Y88487D03*
X206775Y348954D03*
X173508Y348462D03*
X172818Y288683D03*
X184188Y340638D03*
X162135Y332650D03*
X152663Y272053D03*
X168010Y267909D03*
X154300Y227900D03*
X163550Y179657D03*
X200100Y101200D03*
X152350Y131084D03*
X212028Y93512D03*
X201614Y89932D03*
X210680Y84396D03*
X210356Y99104D03*
X197900Y82000D03*
X220131Y58163D03*
X84100Y769000D03*
X85000Y775900D03*
X85300Y755100D03*
X84900Y747900D03*
X83500Y640044D03*
Y653600D03*
X83960Y632636D03*
X85654Y659044D03*
X128918Y307533D03*
X148834Y284832D03*
X140103Y328216D03*
X117460Y335158D03*
X128964Y339470D03*
X148102Y338366D03*
X84863Y229783D03*
X109400Y225400D03*
X90813D03*
X79800Y225900D03*
X144950Y177338D03*
X93303Y154970D03*
X113815Y194333D03*
X132500Y124600D03*
X106300Y105900D03*
X117500Y106200D03*
X111700Y106100D03*
X47100Y746000D03*
X60122Y747800D03*
X64000Y765600D03*
X59379Y644787D03*
X57500Y662600D03*
X72677Y528615D03*
X63862Y512438D03*
X38800Y535700D03*
X79189Y235119D03*
X50500Y243100D03*
X33400Y266400D03*
X59258Y246890D03*
X60069Y237965D03*
X64700Y215100D03*
X51600Y217000D03*
X74700Y191700D03*
X39800Y172900D03*
X29600Y200100D03*
X31500Y185700D03*
X42700Y110500D03*
X219492Y517832D03*
X224515Y532633D03*
X268215Y490733D03*
X288586Y493703D03*
X428343Y463067D03*
X435138Y460661D03*
X471410Y490049D03*
G54D33*
X41142Y773780D03*
Y753780D03*
Y763780D03*
Y655669D03*
Y145669D03*
Y155669D03*
Y135669D03*
X30854Y66929D03*
Y74803D03*
Y82677D03*
Y90551D03*
Y98425D03*
Y106299D03*
X22980Y66929D03*
Y74803D03*
Y82677D03*
Y90551D03*
Y98425D03*
Y106299D03*
X30854Y59055D03*
X22980D03*
G54D29*
X366982Y818335D03*
Y828335D03*
X356982Y818335D03*
X346982Y828335D03*
X356982D03*
X276982Y818335D03*
Y828335D03*
G54D36*
X144843Y860234D03*
Y812994D03*
G54D37*
Y874449D03*
Y798779D03*
X54724Y738189D03*
Y675197D03*
Y620079D03*
Y557087D03*
G54D31*
X182681Y560832D03*
Y580832D03*
G54D38*
X-33503Y269685D03*
G54D40*
X590990Y486293D03*
G54D32*
X155512Y905512D03*
X108268D03*
X76772Y19685D03*
X29528D03*
G54D39*
X-7913Y277559D03*
X-59094D03*
G54D30*
X168465Y876397D03*
Y796831D03*
X109410Y876397D03*
Y796831D03*
%LPD*%
G75*
G54D10*
G01X70200Y199300D02*
X72900Y202000D01*
X82500D01*
X84200Y200300D01*
X117200D01*
X118100Y201200D01*
X128700D01*
X130100Y202600D01*
X321100D01*
X507200Y388700D01*
X517041D01*
G01X499764Y411324D02*
X536928D01*
X-1011811Y-15748D03*
Y940945D03*
X-59094Y277559D03*
X-7913D03*
X-33503Y269685D03*
X54724Y557087D03*
Y620079D03*
Y675197D03*
Y738189D03*
X144843Y798779D03*
Y812994D03*
Y874449D03*
Y860234D03*
X716535Y39370D03*
X775591Y-15748D03*
Y940944D03*
G54D20*
G01X94092Y492819D02*
X92277Y491004D01*
Y478484D01*
X92476Y478285D01*
Y466729D01*
X93065Y466140D01*
Y462823D01*
X98597Y457291D01*
G54D11*
X-138100Y222300D03*
Y241300D03*
Y260300D03*
Y279300D03*
Y298300D03*
Y317300D03*
Y336300D03*
X-70100Y222300D03*
X-87100D03*
X-104100D03*
X-121100D03*
X-70100Y241300D03*
X-87100D03*
X-104100D03*
X-121100D03*
X-70100Y260300D03*
X-87100D03*
X-104100D03*
X-121100D03*
X-70100Y279300D03*
X-87100D03*
X-104100D03*
X-121100D03*
X-70100Y298300D03*
X-87100D03*
X-104100D03*
X-121100D03*
X-70100Y317300D03*
X-87100D03*
X-104100D03*
X-121100D03*
X-70100Y336300D03*
X-87100D03*
X-104100D03*
X-121100D03*
X-2100Y222300D03*
X-19100D03*
X-36100D03*
X-53100D03*
X-2100Y241300D03*
X-19100D03*
X-36100D03*
X-53100D03*
X-2100Y260300D03*
X-19100D03*
X-36300Y260000D03*
X-53100Y260300D03*
X9243Y334400D03*
X-1900Y288300D03*
X-49400Y284500D03*
X-19600Y279500D03*
X-36100Y279300D03*
X-2100Y298300D03*
X-19100D03*
X-36100D03*
X-53100D03*
X-2100Y317300D03*
X-19100D03*
X-36100D03*
X-53100D03*
X-2100Y336300D03*
X-19100D03*
X-36100D03*
X-53100D03*
X-1600Y413600D03*
Y394600D03*
Y375600D03*
Y356600D03*
X-52600Y413600D03*
X-35600D03*
X-18600D03*
X-52600Y394600D03*
X-35600D03*
X-18600D03*
X-52600Y375600D03*
X-35600D03*
X-18600D03*
X-52600Y356600D03*
X-35600D03*
X-18600D03*
X-19400Y483400D03*
X-2400D03*
X-36400D03*
X-53400D03*
X-1500Y470300D03*
Y451300D03*
Y432300D03*
X-52500Y470300D03*
X-35500D03*
X-18500D03*
X-52500Y451300D03*
X-35500D03*
X-18500D03*
X-52500Y432300D03*
X-35500D03*
X-18500D03*
X8788Y453864D03*
X-19400Y502400D03*
X-2400D03*
X-36400D03*
X-53400D03*
X63400Y89300D03*
X51900Y83600D03*
X43980Y86200D03*
X68000Y87750D03*
X42700Y110500D03*
X67300Y107200D03*
X63100Y107300D03*
X48100Y133900D03*
X59200Y95573D03*
X51800Y93500D03*
X79600Y91500D03*
X51900Y89900D03*
X79500Y85700D03*
X77200Y95500D03*
X69800Y176800D03*
X31500Y185700D03*
X76250Y148850D03*
X70200Y199300D03*
X47900Y145500D03*
X48100Y153800D03*
X43800Y204800D03*
X38800Y194300D03*
X38700Y199700D03*
X73700D03*
X49500Y169300D03*
X61751Y181464D03*
X44100Y200600D03*
X49286Y203671D03*
X69000Y202700D03*
X77200Y189000D03*
X60200Y193550D03*
X29600Y200100D03*
X26100Y187300D03*
X39800Y172900D03*
X27800Y191100D03*
X74700Y191700D03*
X70675Y145000D03*
X60009Y255077D03*
X55624Y255132D03*
X59523Y271123D03*
X60102Y263180D03*
X55883Y263570D03*
X33400Y266400D03*
X59258Y246890D03*
X60069Y237965D03*
X64700Y215100D03*
X51600Y217000D03*
X50500Y243100D03*
X70636Y272953D03*
X79189Y235119D03*
X43900Y209000D03*
X72001Y265901D03*
X69400Y207400D03*
X76019Y222534D03*
X42507Y296616D03*
X59316Y300366D03*
X59096Y289139D03*
X59523Y281330D03*
X52257Y276649D03*
X55420Y288656D03*
X17100Y311700D03*
X43181Y278603D03*
X39563Y307968D03*
X21876Y282289D03*
X41418Y287473D03*
X61776Y367194D03*
X43345Y386857D03*
X43639Y374043D03*
X29700Y355000D03*
X27284Y358500D03*
X67527Y381818D03*
X43569Y379314D03*
X65605Y367307D03*
X51422Y473540D03*
X24315Y472668D03*
X47307Y465104D03*
X29064Y471345D03*
X55295Y479672D03*
X20715Y485712D03*
X20276Y477090D03*
X20928Y453864D03*
X21300Y468000D03*
X38800Y535700D03*
X38200Y528900D03*
X51383Y514037D03*
X63862Y512438D03*
X73542Y514340D03*
X37200Y513500D03*
X32026Y516764D03*
X60800Y505200D03*
X56121Y494271D03*
X21090Y497108D03*
X54659Y513125D03*
X67140Y511501D03*
X50893Y534434D03*
X66300Y548000D03*
X67244Y535455D03*
X72677Y528615D03*
X69220Y614992D03*
X59379Y644787D03*
X57500Y662600D03*
X47000Y645300D03*
X69911Y676938D03*
X73900Y664900D03*
X77000Y646200D03*
X72930Y645818D03*
X67257Y643668D03*
X60122Y747800D03*
X64000Y765600D03*
X47100Y746000D03*
X69217Y732676D03*
X73325Y760926D03*
X67809Y758190D03*
X65447Y711413D03*
X62066Y711051D03*
X65356Y707010D03*
X61193Y706973D03*
X73282Y778907D03*
X106300Y105900D03*
X81150Y120850D03*
X89400Y120800D03*
X85250Y120850D03*
X117500Y106200D03*
X85000Y107800D03*
X111700Y106100D03*
X89000Y107700D03*
X82400Y89500D03*
X132500Y124600D03*
X83800Y188800D03*
X111482Y202800D03*
X113815Y194333D03*
X122400Y199000D03*
X80685Y192398D03*
X84641Y204036D03*
X79900Y148700D03*
X103300Y160900D03*
X112000Y160700D03*
X119900Y162200D03*
X125300Y162300D03*
X122100Y203300D03*
X96900Y189286D03*
X107771Y182699D03*
X145400Y161955D03*
X114700Y157000D03*
X107672Y156597D03*
X98700Y156200D03*
X122200Y156700D03*
X80207Y139965D03*
X81200Y176000D03*
X93303Y154970D03*
X144950Y177338D03*
X85713Y151540D03*
X84900Y145300D03*
X125700Y225200D03*
X121000Y225300D03*
X109400Y225400D03*
X90813D03*
X79800Y225900D03*
X87227Y242891D03*
X87263Y264658D03*
X90652Y265960D03*
X87698Y246708D03*
X94051Y265872D03*
X91230Y247047D03*
X91819Y250396D03*
X94793Y252595D03*
X98211Y252758D03*
X142933Y251431D03*
X132651Y255357D03*
X138228Y260175D03*
X124933Y270414D03*
X136427Y251413D03*
X124874Y273953D03*
X137809Y247647D03*
X135592Y257933D03*
X116566Y254205D03*
X114229Y270684D03*
X119242Y252107D03*
X112042Y275903D03*
X121685Y249741D03*
X121741Y246341D03*
X118219Y274497D03*
X122572Y258147D03*
X121599Y274869D03*
X130567Y258051D03*
X113558Y261260D03*
X111008Y242830D03*
X106381Y259865D03*
X106504Y243329D03*
X103610Y268626D03*
X102713Y242975D03*
X103003Y260260D03*
X108652Y247260D03*
X107887Y266647D03*
X101242Y265901D03*
X100415Y246679D03*
X126611Y258265D03*
X84863Y229783D03*
X134529Y264470D03*
X137190Y266587D03*
X131901Y267444D03*
X132163Y271041D03*
X137690Y273752D03*
X110610Y206436D03*
X125600Y221200D03*
X113863Y228669D03*
X102559Y228575D03*
X97885Y228339D03*
X147013Y225483D03*
X122000Y207300D03*
X94600Y206900D03*
X94548Y211258D03*
X109534Y314564D03*
X92682Y331571D03*
X140103Y328216D03*
X117460Y335158D03*
X128964Y339470D03*
X148102Y338366D03*
X119603Y285731D03*
X124478Y280855D03*
X95202Y290958D03*
X98565Y290455D03*
X102107Y290439D03*
X105603Y291092D03*
X95146Y279609D03*
X110808Y291075D03*
X98546Y279609D03*
X114915Y290203D03*
X104413Y278608D03*
X117027Y278475D03*
X148834Y284832D03*
X107750Y277953D03*
X128918Y307533D03*
X135308Y276806D03*
X139784Y276432D03*
X142241Y278783D03*
X121477Y314973D03*
X135613Y308903D03*
X95400Y383083D03*
X84200Y380000D03*
X118744Y525279D03*
X140399Y525238D03*
X129199Y525271D03*
X107103Y525057D03*
X95599Y525026D03*
X84799Y524898D03*
X90878Y585185D03*
X85654Y659044D03*
X83960Y632636D03*
X90681Y690157D03*
X90174Y678675D03*
X85600Y647837D03*
X83500Y653600D03*
Y640044D03*
X84900Y747900D03*
X93840Y699686D03*
X90814Y734451D03*
X91027Y724985D03*
X91094Y715818D03*
X84703Y758885D03*
X84182Y764879D03*
X90746Y712435D03*
X90947Y709040D03*
X91003Y705214D03*
X91130Y701741D03*
X85300Y755100D03*
X85000Y775900D03*
X84100Y769000D03*
X220131Y58163D03*
X197900Y82000D03*
X201237Y106350D03*
X210356Y99104D03*
X210680Y84396D03*
X201614Y89932D03*
X212028Y93512D03*
X212800Y125800D03*
X182400Y128300D03*
X175598Y128436D03*
X220100Y123600D03*
X166700Y128800D03*
X172200Y128300D03*
X179000D03*
X205628Y89404D03*
X152350Y131084D03*
X204849Y106438D03*
X200100Y101200D03*
X170302Y147100D03*
X158100Y166800D03*
X160311Y141680D03*
X219548Y174651D03*
X189600Y166700D03*
X189700Y170200D03*
X190018Y173586D03*
X188961Y162715D03*
X211700Y181600D03*
X208200Y153500D03*
X203900D03*
X200100Y146500D03*
Y150400D03*
X199100Y153800D03*
X194800D03*
X174339Y151172D03*
X178400Y152300D03*
X167015Y167633D03*
X163550Y179657D03*
X172645Y179104D03*
X177087Y178920D03*
X183120Y266103D03*
X183082Y271969D03*
X182853Y256107D03*
X183956Y261452D03*
X168010Y267909D03*
X219717Y211198D03*
X182177Y251208D03*
X154300Y227900D03*
X171200Y233000D03*
X185563Y245456D03*
X175064Y232857D03*
X185740Y240983D03*
X185502Y237383D03*
X152663Y272053D03*
X192284Y258847D03*
X150666Y243134D03*
X195698Y259749D03*
X196365Y256414D03*
X168324Y246397D03*
X171762Y258345D03*
X167894Y243024D03*
X167760Y239626D03*
X156800Y230500D03*
X152663Y267791D03*
X216335Y218212D03*
X196344Y237383D03*
X196078Y248183D03*
X196021Y244556D03*
X196151Y240983D03*
X151519Y250193D03*
X180641Y231683D03*
X186319Y268076D03*
X183043Y276658D03*
X183707Y289861D03*
X183653Y283162D03*
X184188Y340638D03*
X162135Y332650D03*
X185042Y286734D03*
X167051Y293752D03*
X188273Y285674D03*
X187118Y281963D03*
X163142Y294193D03*
X183466Y294017D03*
X152580Y285530D03*
X172818Y288683D03*
X216178Y411331D03*
X219144Y414536D03*
X195307Y355649D03*
X206775Y348954D03*
X173508Y348462D03*
X177715Y397471D03*
X212500Y395500D03*
X217800Y395900D03*
X200161Y416474D03*
X206142Y413945D03*
X206871Y397177D03*
X210042Y412265D03*
X175767Y380311D03*
X189073Y380379D03*
X185276Y380362D03*
X181242Y380481D03*
X197565Y380257D03*
X203379Y380312D03*
X169600Y380500D03*
X173864Y397677D03*
X213400Y434601D03*
X181980Y458681D03*
X210772Y431456D03*
X200453Y439066D03*
X203186Y451492D03*
X180445Y422567D03*
X176991Y463723D03*
X184750Y427953D03*
X208947Y443700D03*
X196803Y444462D03*
X201400Y434400D03*
X202764Y444274D03*
X190887Y424438D03*
X174500Y424100D03*
X182060Y443776D03*
X211243Y462005D03*
X203406Y454885D03*
X195038Y477148D03*
X180313Y446694D03*
X176915Y446556D03*
X195400Y452051D03*
X208632Y457048D03*
X181034Y427967D03*
X177700Y427300D03*
X184399Y525203D03*
X195499D03*
X206699D03*
X217899Y525103D03*
X162615Y525220D03*
X173537D03*
X151684Y525258D03*
X210223Y501477D03*
X213500Y503600D03*
X216300Y499600D03*
X193016Y496643D03*
X219492Y517832D03*
X219590Y740816D03*
X181642Y837321D03*
Y827853D03*
X181772Y818429D03*
X159926Y813000D03*
X201663Y827680D03*
X201142Y837191D03*
X181081Y856307D03*
X181124Y847013D03*
X200798Y846849D03*
X266700Y46900D03*
X263000Y47000D03*
X257500Y46900D03*
X253800Y47000D03*
X244900Y47300D03*
X248600Y47200D03*
X235000Y47500D03*
X238700Y47400D03*
X225231Y58420D03*
X254498Y88487D03*
X251687Y98033D03*
X261830Y81230D03*
X241101D03*
X256928Y69301D03*
X241132Y85023D03*
X259815Y94233D03*
X248000Y114500D03*
X242488Y88466D03*
X223948Y174292D03*
X246100Y151300D03*
Y155800D03*
Y160400D03*
X231049Y188760D03*
X251700Y135484D03*
X231350Y222067D03*
X238614Y217763D03*
X222496Y222320D03*
X223129Y210901D03*
X224664Y293860D03*
X257400Y403206D03*
X239600Y405600D03*
X237800Y411200D03*
X226576Y401835D03*
X228243Y380358D03*
X231915Y380533D03*
X244928Y367685D03*
X238151Y356092D03*
X228510Y367624D03*
X240715Y380333D03*
X222269Y402278D03*
X228949Y410741D03*
X225421Y410908D03*
X269840Y386256D03*
X239693Y396029D03*
X257500Y399300D03*
X264600Y380500D03*
X270800Y408500D03*
X261300Y402355D03*
X275500Y415400D03*
X264124Y408219D03*
X258267Y408800D03*
X233400Y409700D03*
X255010Y367624D03*
X273554Y386722D03*
X223600Y456200D03*
X246502Y472752D03*
X255622Y461532D03*
X263000Y438800D03*
X260600Y435900D03*
X258299Y432800D03*
X250400Y440000D03*
X249600Y428100D03*
X237700Y458000D03*
X269300Y486200D03*
X249600Y432500D03*
X239000Y440300D03*
X244800Y454500D03*
X229600Y460700D03*
X289200Y445100D03*
X252200Y486700D03*
X290300Y462400D03*
X290011Y456234D03*
X289000Y449200D03*
X221035Y453935D03*
X279120Y440440D03*
X276761Y443421D03*
X277575Y449398D03*
X270714Y458323D03*
X263719Y455536D03*
X259779Y456823D03*
X220768Y418393D03*
X260322Y462288D03*
X256852Y465331D03*
X258221Y469246D03*
X235069Y464940D03*
X257184Y421241D03*
X271342Y440630D03*
X235600Y433300D03*
X264775Y459236D03*
X279789Y432846D03*
X285565Y438912D03*
X250400Y473300D03*
X260481Y473769D03*
X253214Y469048D03*
X228400Y486400D03*
X228001Y474064D03*
X226000Y458700D03*
X249845Y469508D03*
X229300Y442500D03*
X225700Y496800D03*
X226115Y507011D03*
X229513Y507141D03*
X232912Y507242D03*
X224515Y532633D03*
X237336Y531828D03*
X236700Y539300D03*
X240400Y534500D03*
X245800D03*
X241300Y539300D03*
X236300Y535600D03*
X243200Y531700D03*
X288586Y493703D03*
X268215Y490733D03*
X251755Y491731D03*
X270700Y495400D03*
X274315Y497133D03*
X283657Y532832D03*
X280259Y532714D03*
X232200Y492100D03*
X231739Y495469D03*
X248286Y489208D03*
X242100Y489000D03*
X268600Y529800D03*
X256300Y531400D03*
X289400Y511700D03*
X243300Y527900D03*
X247256Y529218D03*
X251700Y531500D03*
X268500Y525800D03*
X238118Y492166D03*
X246132Y492160D03*
X289405Y515437D03*
X228500Y498900D03*
X281183Y592936D03*
X223671Y740896D03*
X228249Y761450D03*
X223129Y764830D03*
X271970Y798668D03*
X282413Y798410D03*
X228021Y787335D03*
X223596Y782163D03*
X236973Y795418D03*
X237950Y774979D03*
X237815Y779065D03*
X226949Y782735D03*
X235169Y791455D03*
X240130Y789012D03*
X277254Y852624D03*
X314000Y405200D03*
X316800Y415900D03*
X299800Y398500D03*
X332600Y400100D03*
X305456Y481787D03*
X335532Y485626D03*
X323215Y485633D03*
X304783Y467192D03*
X295115Y476433D03*
Y473033D03*
X297715Y479588D03*
X306603Y459523D03*
X301437Y426833D03*
X304200Y432600D03*
X300603Y432406D03*
X309200Y444700D03*
X331800Y440400D03*
X331900Y444600D03*
X356700Y437500D03*
X348800D03*
X341500Y437400D03*
X291300Y468600D03*
X308900Y449100D03*
X327900Y438100D03*
X341430Y459351D03*
X345735Y460843D03*
X349800Y460000D03*
X353698Y460323D03*
X357812Y460406D03*
X297238Y429641D03*
X304550Y424222D03*
X300059Y422844D03*
X318015Y493833D03*
X334315Y496733D03*
X330815Y493433D03*
X327115Y489533D03*
X344815Y494933D03*
X321415Y497133D03*
X304000Y538500D03*
X308800Y540925D03*
X350400Y512000D03*
X335600Y511400D03*
X304700Y509500D03*
X317900Y520100D03*
X314628Y517729D03*
X343905Y519116D03*
X324400Y570500D03*
X346510Y796385D03*
X350765D03*
X315696Y798445D03*
X294148Y798547D03*
X305437Y798205D03*
X362793Y77815D03*
Y126096D03*
X381025Y73748D03*
Y120650D03*
X373496Y140021D03*
X365131Y135484D03*
X413900Y396400D03*
X428343Y463067D03*
X420575Y467336D03*
X382695Y467033D03*
Y471133D03*
X388884Y468631D03*
X387143Y462647D03*
X378700Y437600D03*
X371200Y437800D03*
X363800Y437700D03*
X428616Y429466D03*
X391500Y459000D03*
X399900Y458600D03*
X421273Y439381D03*
X361533Y460222D03*
X365241Y460010D03*
X416588Y467839D03*
X361814Y796557D03*
X500295Y401715D03*
X501800Y387600D03*
X473838Y385675D03*
X474106Y382285D03*
X500526Y394177D03*
X473605Y389068D03*
X499764Y411324D03*
X497279Y382551D03*
X435138Y460661D03*
X457091Y486699D03*
X475600Y462100D03*
X452300Y420900D03*
X458900Y446600D03*
X483100Y449900D03*
X488500Y474200D03*
X450300Y459900D03*
X471300Y482200D03*
X449000Y480000D03*
X438316Y449493D03*
X438294Y453811D03*
X501700Y477200D03*
X483530Y541762D03*
X487073Y554094D03*
X482183Y535169D03*
X483008Y500529D03*
X469932Y518034D03*
X447307Y511890D03*
X447090Y497242D03*
X471410Y490049D03*
X498994Y488322D03*
X501802Y490240D03*
X494400Y493600D03*
Y497500D03*
X471650Y493916D03*
X494410Y501344D03*
X458713Y518034D03*
X482200Y529100D03*
X484200Y538000D03*
X483800Y545700D03*
X452652Y495705D03*
X465900Y501200D03*
X523200Y399400D03*
X506100Y380000D03*
X517041Y388700D03*
X513500Y399060D03*
X520900Y388100D03*
X536928Y411324D03*
X514000Y486293D03*
X508306Y428179D03*
X523462Y423957D03*
X503923Y423910D03*
X536736Y418540D03*
X504500Y479500D03*
X514073Y552477D03*
X503300Y539700D03*
X529000Y550500D03*
X502318Y535328D03*
X521002Y555911D03*
X525300Y552800D03*
X516900Y561200D03*
X528000Y562900D03*
X512700Y560000D03*
X637200Y393900D03*
X629100Y536000D03*
X632600Y555200D03*
X636200Y555100D03*
X640100Y550600D03*
X638300Y511800D03*
X641800Y519000D03*
X639500Y521900D03*
X641700Y510300D03*
X662100Y394600D03*
X667979Y486293D03*
X702400Y431500D03*
X698300Y431600D03*
X702000Y485700D03*
X688615Y485133D03*
X693509Y431701D03*
X689111Y431612D03*
X684869Y431611D03*
X680738Y431633D03*
X711409Y467621D03*
X707700Y476500D03*
X707890Y467821D03*
X684259Y476130D03*
X682774Y449737D03*
X667745Y456089D03*
X662604Y463284D03*
X671915Y543133D03*
X694700Y547700D03*
X688800Y540450D03*
X702400Y554800D03*
X705927Y538650D03*
X663600Y535395D03*
X644600Y556700D03*
X652400Y545200D03*
X674375Y509826D03*
X700512Y510204D03*
X643833Y549325D03*
X702000Y546581D03*
X702400Y550600D03*
X684600Y542100D03*
X682015Y493633D03*
X665499Y556600D03*
X651800Y540295D03*
X711400Y515400D03*
X711900Y521500D03*
X675400Y538100D03*
X662200Y547300D03*
X709600Y524100D03*
X658314Y526697D03*
X672168Y538889D03*
X676115Y542633D03*
X712102Y542133D03*
X707589Y515400D03*
X700900Y539500D03*
X669200Y559600D03*
X656817Y567131D03*
X697600Y560000D03*
X701400Y560200D03*
X707391Y564566D03*
X643100Y589900D03*
X689945Y758289D03*
X700989Y759255D03*
X667982Y739870D03*
X681402Y757754D03*
X663575Y742289D03*
X668987Y731465D03*
X691075Y820814D03*
X711116Y796516D03*
X702290Y820921D03*
X680480Y773302D03*
X678755Y784815D03*
X676727Y790555D03*
X679630Y795856D03*
X680239Y802378D03*
X682693Y806283D03*
X684732Y810518D03*
X669886Y786112D03*
X666516Y784722D03*
X686308Y834802D03*
X646342Y826469D03*
X685799Y770894D03*
X690211Y827401D03*
X683715Y852233D03*
X710727Y862002D03*
X678351Y854383D03*
X679332Y841866D03*
X681156Y844982D03*
X681542Y848361D03*
X722687Y120650D03*
X727300Y273200D03*
X758200Y338900D03*
X756700Y370600D03*
X762900Y387400D03*
X768000Y457700D03*
X767700Y473300D03*
X729700Y551500D03*
X729600Y540400D03*
X724000Y532600D03*
X722682Y538700D03*
X716300Y517125D03*
X719800Y525000D03*
X719866Y528656D03*
X751965Y522097D03*
X747886D03*
X757848Y513543D03*
X752874Y534854D03*
X737297Y517903D03*
X756523Y520272D03*
X749493Y535216D03*
X725100Y519600D03*
X746000Y549700D03*
X726800Y527400D03*
X723538Y526440D03*
X742607Y549481D03*
X752100Y506500D03*
X749500Y508800D03*
X742000Y505000D03*
X762275Y512870D03*
X744073Y522097D03*
X755862Y516303D03*
X756400Y508100D03*
X756272Y534995D03*
X763000Y490800D03*
X717879Y564572D03*
X725900Y561800D03*
X737400Y576200D03*
X766358Y564600D03*
X727700Y584400D03*
X758400Y568500D03*
X742600Y577100D03*
X756100Y658700D03*
X757600Y639700D03*
X746669Y740179D03*
X743653Y744114D03*
X741453Y748054D03*
X738850Y751989D03*
X734450Y755929D03*
X730967Y759864D03*
X724305Y770450D03*
X723678Y774016D03*
X727477Y775212D03*
X724733Y779559D03*
X730028Y782297D03*
X724859Y784497D03*
X742663Y788885D03*
X729988Y787114D03*
X739510Y795264D03*
X725239Y788970D03*
X745230Y793211D03*
X729486Y791416D03*
X742370Y799077D03*
X725407Y794540D03*
X747659Y796960D03*
X744790Y802781D03*
X749593Y803991D03*
X747556Y808994D03*
X749629Y812608D03*
X722443Y826463D03*
X721704Y829981D03*
X724858Y831254D03*
X723801Y834857D03*
X726332Y837128D03*
X733066Y836450D03*
X729250Y850000D03*
X721243Y850725D03*
X718263Y863827D03*
X745100Y859405D03*
X721112Y854419D03*
X724093Y840187D03*
X726776Y842277D03*
X733796Y854172D03*
G54D21*
G01X251700Y135484D02*
X245184Y142000D01*
X168300D01*
X164275Y146025D01*
X91228D01*
X85713Y151540D01*
G01X514000Y486293D02*
X667979D01*
G54D12*
X4800Y48600D03*
X5800Y6400D03*
X5000Y71900D03*
Y91900D03*
X5100Y111800D03*
X4900Y130400D03*
X5000Y150500D03*
X5300Y170000D03*
X9151Y473051D03*
X8672Y487593D03*
X7075Y527972D03*
X7927Y509647D03*
X8140Y637282D03*
X8246Y771416D03*
X45700Y61000D03*
X65500Y60800D03*
X75500D03*
X45900Y50000D03*
X65700Y49800D03*
X50800Y39500D03*
X70700Y45800D03*
X55800Y61300D03*
X59900Y40600D03*
X53200Y26300D03*
X50600Y6000D03*
X50500Y67700D03*
X70500Y72000D03*
X60800Y72500D03*
X57200Y175300D03*
X16158Y477255D03*
X39600Y494800D03*
X38200Y490900D03*
X35100Y494400D03*
X33600Y512600D03*
X37329Y524472D03*
X33880Y526500D03*
X33921Y520414D03*
X18809Y491871D03*
X17212Y532250D03*
X18064Y513925D03*
X18277Y641560D03*
X9844Y658803D03*
X19981Y663081D03*
X9631Y753837D03*
X19768Y758115D03*
X18383Y775694D03*
X55459Y780063D03*
X48300Y775300D03*
X87900Y47800D03*
X90900Y42400D03*
X80400Y47800D03*
X124100Y6700D03*
X110800Y48800D03*
X120200Y48400D03*
X98700Y48900D03*
X143900Y38000D03*
X108100Y35300D03*
X146900Y48500D03*
X109700Y6400D03*
X119700Y35400D03*
X139800Y31100D03*
X96300Y6100D03*
X147200Y7300D03*
X108600Y19900D03*
X126500Y20100D03*
X147500Y90200D03*
X142167Y106366D03*
X142101Y98650D03*
X111100Y75500D03*
X100000Y75600D03*
X121700Y75300D03*
X85300Y70200D03*
X126300Y180209D03*
X126700Y173500D03*
X136291Y179968D03*
X136100Y173800D03*
X134200Y217300D03*
X130000Y217200D03*
X134600Y222200D03*
X106051Y767209D03*
X122899Y825236D03*
X112762Y820958D03*
X116188Y771487D03*
X131900Y893200D03*
X120874Y857517D03*
X110737Y853239D03*
X131700Y915700D03*
X89871Y917500D03*
X209100Y51700D03*
X191700Y63300D03*
X209200Y65100D03*
X200700Y51700D03*
X185100Y55900D03*
X208900Y58600D03*
X192000Y55900D03*
X200700Y58300D03*
X184700Y63100D03*
X173200Y10900D03*
X213700Y35200D03*
X186000D03*
X197796Y12653D03*
X160600Y49100D03*
X153200Y48700D03*
X167500Y49000D03*
X160500Y19700D03*
X170400Y31100D03*
X150600Y37800D03*
X154500Y90000D03*
X158000Y79600D03*
X165200Y79500D03*
X163300Y95900D03*
X163500Y105500D03*
X151800Y72400D03*
X209000Y72300D03*
X201500D03*
X177100Y99500D03*
X177200Y104800D03*
X177300Y94200D03*
Y88500D03*
X184700D03*
X190700Y77800D03*
X201200Y65600D03*
X191000Y71300D03*
X184500Y71200D03*
X177400Y71400D03*
X177500Y77900D03*
X183700Y78100D03*
X191500Y88500D03*
X204200Y126700D03*
X206600Y130300D03*
X201900D03*
X207495Y192761D03*
X169800Y155796D03*
X165162Y155909D03*
X169709Y160049D03*
X165388Y160094D03*
X196400Y585300D03*
X179000Y624800D03*
X193600Y702400D03*
X179100Y714600D03*
X202300Y742000D03*
X189273Y902478D03*
X213138Y905780D03*
X218729Y857629D03*
X200460Y913771D03*
X282282Y47189D03*
X286930D03*
X233900Y32500D03*
X252187Y23895D03*
X286651Y14571D03*
X224431Y15210D03*
X248900Y8400D03*
X282444Y106834D03*
X225919Y88394D03*
X225937Y80731D03*
X221710Y80767D03*
X221722Y88431D03*
X230158Y88359D03*
X230123Y80805D03*
X225851Y73774D03*
X221740Y73844D03*
X229870Y73970D03*
X228169Y68374D03*
X224169Y68520D03*
X228728Y96613D03*
X224285Y96750D03*
X258741Y193852D03*
X256823Y221979D03*
X246169Y246270D03*
X230774Y270268D03*
X241694Y274956D03*
X228635Y385956D03*
X232788Y385893D03*
X229764Y513034D03*
X234416Y512963D03*
X238924Y512390D03*
X243100Y516300D03*
X245963Y511890D03*
X250975Y511729D03*
X255500Y514000D03*
X264000Y513400D03*
X277300Y572500D03*
X259600Y568400D03*
X271949Y648699D03*
X272588Y681087D03*
X244248Y682153D03*
X255542Y665532D03*
X241904Y652321D03*
X289634Y659352D03*
X284520Y743307D03*
X282176Y713475D03*
X230823Y823850D03*
X253623Y867319D03*
X254262Y899707D03*
X225922Y900773D03*
X237216Y884152D03*
X223578Y870941D03*
X285585Y897363D03*
X283241Y867531D03*
X264212Y903112D03*
X299300Y41300D03*
X321300Y43200D03*
X351800Y42200D03*
X360500Y42600D03*
X330000Y42800D03*
X329900Y37100D03*
X321300D03*
X360500Y36700D03*
X291373Y47394D03*
X299300Y46400D03*
X351800Y36300D03*
X299600Y62100D03*
X351900Y62000D03*
X360200Y62300D03*
X329500Y62600D03*
X321300Y63100D03*
X325006Y15636D03*
X299500Y68200D03*
X352000Y68000D03*
X360200Y68200D03*
X329600D03*
X321400Y68500D03*
X344663Y108965D03*
X312275Y98098D03*
X354197Y158187D03*
X301140Y161383D03*
X352066Y262596D03*
X307320Y223390D03*
X301781Y258122D03*
X322022Y279856D03*
X320207Y428442D03*
X320166Y432442D03*
X309648Y582024D03*
X319679Y655730D03*
X320318Y688118D03*
X291978Y689184D03*
X303272Y672563D03*
X347378Y688332D03*
X358672Y671711D03*
X345034Y658500D03*
X302115Y693462D03*
X360803Y704312D03*
X333102Y737766D03*
X344396Y721145D03*
X330758Y707934D03*
X312221Y709853D03*
X312860Y742241D03*
X295814Y726686D03*
X319171Y767846D03*
X313959Y724732D03*
X354623Y896937D03*
X352279Y867105D03*
X313286Y863909D03*
X313925Y896297D03*
X296879Y880742D03*
X332436Y858576D03*
X337648Y901690D03*
X382100Y61900D03*
X401343Y58465D03*
X394098Y20059D03*
X362775D03*
X412506Y33484D03*
X382200Y68500D03*
X410025Y87658D03*
X390208Y180135D03*
X366982Y198886D03*
X407769Y204757D03*
X384668Y247681D03*
X376144Y279856D03*
X380956Y408290D03*
X376513Y408085D03*
X371865D03*
X380392Y416962D03*
X375949Y416757D03*
X371301D03*
X366653Y416484D03*
X367217Y407812D03*
X366719Y424200D03*
X371367Y424473D03*
X376015D03*
X380458Y424678D03*
X414894Y453432D03*
X419296Y449111D03*
X423572Y453454D03*
X419092Y457572D03*
X419225Y453324D03*
X410200Y474200D03*
X410179Y469769D03*
X375079Y654878D03*
X375718Y687266D03*
X430267Y679595D03*
X413860Y696428D03*
X400222Y683217D03*
X388817Y692040D03*
X420252Y725194D03*
X420891Y757582D03*
X392551Y758648D03*
X403845Y742027D03*
X390207Y728816D03*
X361442Y736700D03*
X430906Y711983D03*
X402566Y713049D03*
X395450Y767846D03*
X378868Y723311D03*
X421530Y814262D03*
X419186Y784430D03*
X429202Y894806D03*
X426858Y864974D03*
X382324Y863483D03*
X382963Y895871D03*
X365917Y880316D03*
X413927Y901690D03*
X397345Y857155D03*
X432682Y23909D03*
X472315Y23056D03*
X496393Y55871D03*
X457399Y46069D03*
X496109Y93412D03*
X457989Y78967D03*
X493200Y145500D03*
X451789Y154565D03*
X473097Y208901D03*
X453252Y250240D03*
X438300Y481200D03*
X434515Y483333D03*
X434412Y479334D03*
X432014Y476132D03*
X455846Y546626D03*
X465212Y726260D03*
X465851Y758648D03*
X437511Y759714D03*
X448805Y743093D03*
X435167Y729882D03*
X474587Y765253D03*
X445197Y719047D03*
X449231Y780808D03*
X449870Y813196D03*
X432824Y797641D03*
X476931Y795085D03*
X488225Y778464D03*
X499945Y828325D03*
X486307Y815114D03*
X456903Y861352D03*
X457542Y893740D03*
X440496Y878185D03*
X488651Y844946D03*
X499208Y899795D03*
X463674Y852891D03*
X557547Y24335D03*
X526213Y34431D03*
X555558Y100229D03*
X531425Y77545D03*
X545330Y147959D03*
X521476Y205704D03*
X509632Y174434D03*
X526688Y248818D03*
X566000Y536700D03*
X508224Y580873D03*
X549379Y653173D03*
X504632Y761631D03*
X505271Y794019D03*
X516352Y811492D03*
X562377Y833013D03*
X532332Y836635D03*
X516991Y843880D03*
X563016Y865401D03*
X534676Y866467D03*
X545970Y849846D03*
X545118Y880530D03*
X528711Y897363D03*
X515073Y884152D03*
X562590Y881808D03*
X510579Y854786D03*
X545757Y912918D03*
X517417Y913984D03*
X564934Y911640D03*
X573457Y59531D03*
X621826Y20111D03*
X591122Y33010D03*
X607704Y77545D03*
X586385Y204283D03*
X596334Y173012D03*
X602967Y248818D03*
X633923Y520400D03*
X587942Y582024D03*
X614582Y653599D03*
X604141Y675547D03*
X578784Y682152D03*
X582620Y653386D03*
X632693Y697281D03*
X607550Y703460D03*
X628006Y720720D03*
X592635Y878186D03*
X576228Y895019D03*
X640791Y876268D03*
X641430Y908656D03*
X613090Y909722D03*
X624384Y893101D03*
X610746Y879890D03*
X593274Y910574D03*
X660180Y56547D03*
X657451Y28746D03*
X703700Y30300D03*
X651658Y95968D03*
X692985Y75650D03*
X699619Y201914D03*
X652714Y200019D03*
X692512Y162589D03*
X661673Y260892D03*
X688248Y246923D03*
X712386Y297542D03*
X711500Y438300D03*
X694995Y453626D03*
X694923Y461253D03*
X694851Y469456D03*
X694907Y476993D03*
X644900Y538300D03*
X668135Y523360D03*
X672161Y528021D03*
X676550Y523677D03*
X672342Y519560D03*
X672257Y523769D03*
X678293Y698772D03*
X675736Y657222D03*
X694061Y681726D03*
X654641Y691101D03*
X643987Y664041D03*
X697897Y662763D03*
X708231Y730948D03*
X681276Y722211D03*
X650805Y716671D03*
X698962Y707936D03*
X692356Y875629D03*
X692995Y908017D03*
X664655Y909083D03*
X675949Y892462D03*
X662311Y879251D03*
X754800Y56800D03*
Y36800D03*
Y16800D03*
X723466Y60810D03*
X721334Y17767D03*
X754800Y76800D03*
X754700Y117600D03*
Y97600D03*
X734333Y88085D03*
X754700Y197600D03*
Y177600D03*
Y157600D03*
Y137600D03*
Y257600D03*
Y237600D03*
Y217600D03*
Y277600D03*
X753800Y303200D03*
X767300Y340400D03*
X766900Y333754D03*
X735134Y289819D03*
X767000Y410900D03*
X766700Y403500D03*
X766900Y395400D03*
Y387800D03*
Y364600D03*
Y356300D03*
X767600Y348500D03*
X767400Y481600D03*
Y465900D03*
X767500Y450800D03*
X767300Y441747D03*
X766500Y435100D03*
X766800Y427000D03*
X767100Y418700D03*
Y544600D03*
X766800Y535700D03*
X767200Y524500D03*
X766900Y497700D03*
X767200Y489700D03*
X767100Y623900D03*
Y614800D03*
X766700Y606900D03*
X767700Y600200D03*
X766700Y592700D03*
X767000Y584300D03*
Y576100D03*
Y569500D03*
X726000Y650700D03*
X720000Y650800D03*
X733000Y650600D03*
X740000D03*
X766900Y639500D03*
Y631900D03*
X715795Y697494D03*
X750300Y663000D03*
X740513Y687906D03*
X745733Y713048D03*
X764200Y813000D03*
X745413Y854763D03*
X716221Y876694D03*
X729859Y889905D03*
X718565Y906526D03*
X746905Y905460D03*
X746266Y873072D03*
G54D22*
G01X6614Y549842D02*
Y553544D01*
G01D02*
Y557246D01*
G01Y553544D02*
X10316D01*
G01X6849Y623622D02*
X10551D01*
G01X6614Y667952D02*
Y671654D01*
G01D02*
Y675356D01*
G01Y671654D02*
X10316D01*
G01X6849Y741732D02*
X10551D01*
G01X76772Y7633D02*
Y19685D01*
G01D02*
Y31737D01*
G01X64720Y19685D02*
X76772D01*
G01D02*
X88824D01*
G01X29528Y7633D02*
Y19685D01*
G01D02*
Y31737D01*
G01X17476Y19685D02*
X29528D01*
G01D02*
X41580D01*
G01X30854Y106299D02*
Y110201D01*
G01Y106299D02*
X34756D01*
G01X32204Y549842D02*
Y553544D01*
G01D02*
Y557246D01*
G01Y553544D02*
X35906D01*
G01X18425Y549842D02*
Y553544D01*
G01D02*
Y557246D01*
G01X14723Y553544D02*
X18425D01*
G01D02*
X22127D01*
G01X32204Y619920D02*
Y623622D01*
G01D02*
X35906D01*
G01X18425Y619920D02*
Y623622D01*
G01D02*
Y627324D01*
G01X14723Y623622D02*
X18425D01*
G01D02*
X22127D01*
G01X10551Y619920D02*
Y623622D01*
G01D02*
Y627324D01*
G01Y623622D02*
X14253D01*
G01X32204Y667952D02*
Y671654D01*
G01D02*
Y675356D01*
G01X28502Y671654D02*
X32204D01*
G01D02*
X35906D01*
G01X18425Y667952D02*
Y671654D01*
G01D02*
Y675356D01*
G01X14723Y671654D02*
X18425D01*
G01D02*
X22127D01*
G01X32204Y738030D02*
Y741732D01*
G01D02*
Y745434D01*
G01X28502Y741732D02*
X32204D01*
G01D02*
X35906D01*
G01X18425Y738030D02*
Y741732D01*
G01D02*
Y745434D01*
G01X14723Y741732D02*
X18425D01*
G01D02*
X22127D01*
G01X10551Y738030D02*
Y741732D01*
G01D02*
Y745434D01*
G01Y741732D02*
X14253D01*
G01X109410Y789679D02*
Y796831D01*
G01D02*
Y803983D01*
G01X102258Y796831D02*
X109410D01*
G01D02*
X116562D01*
G01X143460Y905512D02*
X155512D01*
G01X108268Y893460D02*
Y905512D01*
G01D02*
Y917564D01*
G01X96216Y905512D02*
X108268D01*
G01D02*
X120320D01*
G01X109410Y869245D02*
Y876397D01*
G01D02*
Y883549D01*
G01X102258Y876397D02*
X109410D01*
G01D02*
X116562D01*
G01X182681Y556680D02*
Y560832D01*
G01D02*
Y564984D01*
G01X178529Y560832D02*
X182681D01*
G01D02*
X186833D01*
G01X182681Y576680D02*
Y580832D01*
G01D02*
Y584984D01*
G01X178529Y580832D02*
X182681D01*
G01D02*
X186833D01*
G01X168465Y789679D02*
Y796831D01*
G01D02*
Y803983D01*
G01X161313Y796831D02*
X168465D01*
G01D02*
X175617D01*
G01X168465Y869245D02*
Y876397D01*
G01D02*
Y883549D01*
G01X161313Y876397D02*
X168465D01*
G01D02*
X175617D01*
G01X155512Y893460D02*
Y905512D01*
G01D02*
Y917564D01*
G01Y905512D02*
X167564D01*
G01X286982Y828335D02*
Y832787D01*
G01X282530Y828335D02*
X286982D01*
G01D02*
X291434D01*
G01X296982D02*
Y832787D01*
G01X292530Y828335D02*
X296982D01*
G01D02*
X301434D01*
G01X306982D02*
Y832787D01*
G01X302530Y828335D02*
X306982D01*
G01D02*
X311434D01*
G01X316982D02*
Y832787D01*
G01X312530Y828335D02*
X316982D01*
G01D02*
X321434D01*
G01X326982D02*
Y832787D01*
G01X322530Y828335D02*
X326982D01*
G01D02*
X331434D01*
G01X336982D02*
Y832787D01*
G01X332530Y828335D02*
X336982D01*
G01D02*
X341434D01*
G01X346982Y823883D02*
Y828335D01*
G01D02*
Y832787D01*
G01X342530Y828335D02*
X346982D01*
G01D02*
X351434D01*
G01X356982Y823883D02*
Y828335D01*
G01D02*
Y832787D01*
G01X352530Y828335D02*
X356982D01*
G01D02*
X361434D01*
G01X366982Y823883D02*
Y828335D01*
G01D02*
Y832787D01*
G01X362530Y828335D02*
X366982D01*
G01D02*
X371434D01*
G54D13*
G01X-771361Y-182763D02*
Y-262763D01*
G01Y-218263D02*
X373639D01*
G01X-771361Y-262763D02*
X373639D01*
G01X-775361Y-166763D02*
G02I-12000J0D01*
G01X-780511D02*
G02I-6850J0D01*
G01X-787361Y-182763D02*
Y-150763D01*
G01X-771361Y-166763D02*
X-803361D01*
G01X-771361Y-182763D02*
X373639D01*
G01X-413861D02*
Y-262763D01*
G01X-276361Y-182763D02*
Y-262763D01*
G01X-161361Y-182763D02*
Y-262763D01*
G01X6139Y-182763D02*
Y-262763D01*
G01X57200Y175300D02*
X59800Y172700D01*
X82700D01*
X89000Y179000D01*
X125091D01*
X126300Y180209D01*
G01X32026Y516764D02*
Y516908D01*
X30861Y518073D01*
Y543539D01*
X26600Y547800D01*
Y626500D01*
X31099Y630999D01*
X43499D01*
X47200Y634700D01*
Y645100D01*
X47000Y645300D01*
G01X176139Y-182763D02*
Y-262763D01*
G01X373639Y-182763D02*
Y-262763D01*
G01X401639Y-166763D02*
G02I-12000J0D01*
G01X396489D02*
G02I-6850J0D01*
G01X389639Y-182763D02*
Y-150763D01*
G01X405639Y-166763D02*
X373639D01*
G01X387143Y462647D02*
X411195Y486699D01*
X457091D01*
G01X682774Y449737D02*
X682988Y449951D01*
X708059D01*
G01X707700Y476500D02*
Y476789D01*
X704372Y480117D01*
X688246D01*
X684259Y476130D01*
X8789Y376072D03*
X6944Y414616D03*
X6855Y436844D03*
X6750Y425868D03*
X7180Y449205D03*
X62439Y413744D03*
X66931Y398350D03*
X74863Y390483D03*
X64055Y389700D03*
X33722Y401639D03*
X74544Y414071D03*
X70779Y402387D03*
X79016Y410283D03*
X35738Y406956D03*
X14422Y411528D03*
X14657Y416838D03*
X10615Y411073D03*
X26551Y394546D03*
X30232Y416556D03*
X23922Y415548D03*
X35994Y410146D03*
X43719Y414419D03*
X32141Y407501D03*
X31808Y410684D03*
X18448Y402542D03*
X74817Y409752D03*
X26972Y399588D03*
X70882Y409794D03*
X66938Y410045D03*
X78939Y414083D03*
X18448Y406788D03*
X53976Y389814D03*
X74894Y398251D03*
X62031Y399713D03*
X70775Y398396D03*
X70845Y405839D03*
X70952Y414050D03*
X54515Y396433D03*
X54463Y386651D03*
X70865Y390502D03*
X74702Y394300D03*
X74869Y406315D03*
X78300Y386505D03*
X64948Y386626D03*
X78362Y398337D03*
X77963Y381183D03*
X70888Y394222D03*
X66963Y473083D03*
X66931Y484968D03*
X79081Y465348D03*
X70704Y429620D03*
X67015Y449433D03*
X74639Y441855D03*
X78754Y453353D03*
X78811Y426113D03*
X52151Y456887D03*
X66903Y457689D03*
X78798Y433983D03*
X17072Y435057D03*
X74836Y453477D03*
X59980Y482517D03*
X78754Y449904D03*
X67112Y481066D03*
X70488Y465291D03*
X74450Y457429D03*
X70713Y461504D03*
X36237Y441728D03*
X70908Y457771D03*
X70898Y418271D03*
X61038Y424878D03*
X74726Y425594D03*
X59209Y438908D03*
X46853Y441796D03*
X78561Y421756D03*
X70809Y438057D03*
X43659Y432766D03*
X43088Y438073D03*
X45486Y456341D03*
X38566Y451290D03*
X42312Y463368D03*
X74780Y429794D03*
X24357Y423051D03*
X37988Y438328D03*
X19757Y418538D03*
X29472Y428016D03*
X78738Y429679D03*
X11964Y421332D03*
X52476Y439395D03*
X13062Y429279D03*
X74656Y421838D03*
X17936Y431103D03*
X14206Y433632D03*
X15424Y422722D03*
X70857Y433857D03*
X19015Y426461D03*
X14147Y438989D03*
X74752Y437655D03*
X74437Y473159D03*
X15872Y441916D03*
X74460Y461287D03*
X78793Y445704D03*
X70868Y477094D03*
X23748Y436249D03*
X26611Y441743D03*
X70909Y469595D03*
X30513Y437850D03*
X74702Y469183D03*
X37420Y461517D03*
X31517Y445328D03*
X70868Y473157D03*
X28472Y447107D03*
X48298Y454813D03*
X70602Y453533D03*
X79050Y457367D03*
X74805Y481031D03*
X66991Y476766D03*
X62798Y461555D03*
X74451Y465323D03*
X79094Y441620D03*
X74801Y433368D03*
X70869Y421840D03*
X70759Y449277D03*
X74805Y477094D03*
X70868Y481031D03*
X74598Y485021D03*
X78421Y473078D03*
X74695Y449260D03*
X59063Y485583D03*
X79134Y461339D03*
X78742Y488905D03*
X66961Y488885D03*
X74805Y492842D03*
X74870Y488789D03*
X69523Y567387D03*
X69555Y564187D03*
X69569Y594959D03*
X69520Y560987D03*
X68421Y570392D03*
X69323Y579887D03*
X69518Y604727D03*
X69599Y601527D03*
X69569Y598159D03*
X69388Y576660D03*
X69450Y573460D03*
X69569Y608021D03*
X69496Y611417D03*
X69661Y591387D03*
X66579Y592250D03*
X63125Y592801D03*
X62681Y589462D03*
X69451Y684303D03*
Y681103D03*
X68928Y687846D03*
X69316Y697605D03*
X69451Y691003D03*
X69474Y694403D03*
X69523Y718313D03*
Y715113D03*
X69472Y729385D03*
X69548Y726185D03*
X69558Y711913D03*
X68620Y722610D03*
X106419Y310245D03*
X126184Y310860D03*
X93200Y308800D03*
X145771Y414191D03*
X82555Y406288D03*
X110472Y394496D03*
X145765Y406438D03*
X122053Y406224D03*
X114175Y410161D03*
X125990Y394413D03*
X141738D03*
X98427Y414098D03*
X125990D03*
X90553Y410161D03*
X102263Y414083D03*
X141887Y410202D03*
X102364Y406224D03*
X133864Y410161D03*
X94367Y394479D03*
X102364Y402287D03*
X106301Y398350D03*
Y402287D03*
X102364Y398350D03*
X110238Y402287D03*
X114175D03*
X110238Y398350D03*
X114175D03*
X85721Y385798D03*
X149362Y413951D03*
X149498Y406396D03*
X145795Y410173D03*
X149431Y394402D03*
X149783Y390487D03*
X110238Y410161D03*
X141738Y414098D03*
X133863Y413773D03*
X114175Y414098D03*
X122053D03*
X125990Y410161D03*
X94579Y406324D03*
X118130Y398511D03*
X98427Y410161D03*
X90553Y414098D03*
X86563Y402383D03*
X133964Y394555D03*
X102555Y394412D03*
X86616Y394413D03*
X86463Y390483D03*
X114175Y406224D03*
X126063Y406183D03*
X141738Y406224D03*
X106301D03*
X149663Y410083D03*
X82459Y413976D03*
X90566Y394383D03*
X82663Y402406D03*
X133864Y402287D03*
X86772Y414047D03*
X122053Y402287D03*
X133864Y398350D03*
X137801D03*
X122053D03*
X137801Y402287D03*
X125990D03*
Y398350D03*
X129927Y402287D03*
Y398350D03*
X82663Y398383D03*
X141738Y402287D03*
Y398350D03*
X145865Y402287D03*
Y398350D03*
X149488Y402114D03*
X149583Y398383D03*
X90359Y469275D03*
X137801Y453472D03*
Y445598D03*
X133864Y437720D03*
Y445598D03*
X133953Y425813D03*
X102684Y445671D03*
X106263Y437583D03*
X133864Y433783D03*
X102364Y429846D03*
X98363Y421883D03*
X94263Y418129D03*
X106210Y421976D03*
X110332Y425814D03*
X149612Y445598D03*
Y433783D03*
X86493Y441401D03*
X86616Y433783D03*
X86687Y421669D03*
X137801Y477094D03*
X149612D03*
X114175D03*
X102364D03*
X98626Y477049D03*
X130081Y425912D03*
X121943Y425834D03*
X114091Y425962D03*
X122053Y421972D03*
Y418035D03*
X106301D03*
X114175D03*
X133863Y417883D03*
X117951Y437592D03*
X114175Y445598D03*
X110263Y441683D03*
X118189Y445711D03*
X125990Y445598D03*
X110238Y437720D03*
X125990D03*
X110222Y417989D03*
X106341Y426062D03*
X82564Y449659D03*
X145663Y441483D03*
X98288Y441609D03*
X149612Y429846D03*
X110238Y453472D03*
X122053Y429846D03*
X114063Y429879D03*
X125897Y453240D03*
X118238Y453417D03*
X149594Y480923D03*
X94518Y449186D03*
X86768Y449383D03*
X98427Y484968D03*
Y481031D03*
X102364D03*
Y484968D03*
X106301D03*
Y481031D03*
X114175Y484968D03*
Y481031D03*
X122053Y484968D03*
Y481031D03*
X125990Y484968D03*
Y481031D03*
X145567Y453547D03*
X145763Y449583D03*
X149576Y465497D03*
X98597Y457291D03*
X94490Y429846D03*
X90463Y425983D03*
X90480Y437608D03*
X82562Y425980D03*
X86505Y425987D03*
X90380Y429650D03*
X130080Y457372D03*
X94490Y437720D03*
X82681Y430041D03*
X141827Y461346D03*
X98334Y429754D03*
X98427Y437720D03*
X94369Y425977D03*
X82677Y433595D03*
X149563Y469220D03*
X94490Y433783D03*
X141738Y481031D03*
X82663Y457486D03*
X141738Y484968D03*
X98433Y449125D03*
X137801Y481031D03*
X102600Y425983D03*
X137801Y484968D03*
X94554Y421911D03*
X133864Y481031D03*
X149612Y437720D03*
X94414Y445605D03*
X133864Y484968D03*
X86663Y429536D03*
X82542Y445403D03*
X98427Y433783D03*
X86568Y445669D03*
X90426Y449431D03*
X90563Y417983D03*
X145675Y425909D03*
X82573Y441360D03*
X145675Y437720D03*
X98280Y445405D03*
X90426Y441880D03*
X145675Y481031D03*
Y484968D03*
X145737Y418077D03*
X145675Y473157D03*
Y465283D03*
X149719Y457328D03*
X129927Y473157D03*
Y465283D03*
X137801Y461346D03*
Y457409D03*
X114175Y473157D03*
X122053Y469220D03*
X110263Y469083D03*
X122053Y473157D03*
X90350Y473069D03*
X82679Y477094D03*
X90662Y461604D03*
X106263Y453483D03*
X106449Y465157D03*
X122053Y445598D03*
X126180Y418224D03*
X137801Y437720D03*
X137767Y425993D03*
X129927Y445598D03*
X141738Y449535D03*
X133864Y421972D03*
Y429846D03*
X98533Y418180D03*
X118134Y449362D03*
X106363Y441583D03*
X110238Y445598D03*
X110289Y422113D03*
X122053Y437720D03*
X114175D03*
X94661Y441681D03*
X106263Y433683D03*
X90544Y433408D03*
X90408Y421930D03*
X129927Y437720D03*
X141738Y429846D03*
X86663Y453583D03*
X82732Y453139D03*
X102227Y473344D03*
X145675Y469220D03*
X90376Y476918D03*
X110238Y477094D03*
X141738D03*
X137801Y473157D03*
X98427Y469046D03*
X106301Y469220D03*
X114175D03*
X126057Y469287D03*
X129927Y469220D03*
X137801D03*
X122053Y465283D03*
X133864D03*
X106301Y461346D03*
X122113Y457535D03*
X129963Y461283D03*
X110263Y457283D03*
X122158Y453388D03*
X125990Y477094D03*
X137801Y449535D03*
X149612Y425909D03*
X82535Y461227D03*
X83021Y473118D03*
X141595Y421932D03*
X141775Y426153D03*
X86735Y461382D03*
X141763Y437883D03*
X86937Y477160D03*
X141682Y417902D03*
X82759Y469436D03*
X145663Y445583D03*
X145675Y429846D03*
X142008Y457429D03*
X141863Y445583D03*
X86959Y469276D03*
X137570Y421843D03*
X145561Y421879D03*
X90965Y465270D03*
X129927Y481031D03*
Y484968D03*
X110238Y481031D03*
Y484968D03*
X94490Y481031D03*
X86663Y457283D03*
X94490Y484968D03*
X86765Y465205D03*
X138061Y418151D03*
X145675Y433783D03*
X82763Y417750D03*
X86523Y417943D03*
X94844Y469182D03*
X102469Y469134D03*
X106149Y457371D03*
X141649Y453189D03*
X149620Y485149D03*
X98682Y461441D03*
X94092Y492819D03*
X141738Y488905D03*
X110238D03*
X125990D03*
X94377Y489070D03*
X118004Y488825D03*
X133864Y488905D03*
X149612D03*
X102308Y488978D03*
X86616Y488905D03*
X91852Y563129D03*
X91156Y572112D03*
X90823Y581387D03*
X91343Y598284D03*
X91023Y606587D03*
X90923Y616187D03*
X91198Y595087D03*
X91123Y591887D03*
X91223Y588487D03*
X159768Y238444D03*
X160004Y233894D03*
X181576Y407810D03*
X175463Y413760D03*
X161499Y402554D03*
X169297Y402536D03*
X157502Y390427D03*
X173425Y390228D03*
X214660Y362600D03*
X176751Y387090D03*
X157251Y414149D03*
X161477Y394511D03*
X180991Y398678D03*
X180809Y414170D03*
X179225Y403667D03*
X203410Y394323D03*
X182378Y390377D03*
X157574Y394185D03*
X161241Y398226D03*
X161277Y414114D03*
X174124Y402624D03*
X161213Y390551D03*
X169503Y386977D03*
X153587Y406496D03*
X157554Y402251D03*
X157698Y406313D03*
X161475Y410299D03*
X165266Y409882D03*
X165337Y414489D03*
X153528Y410052D03*
X165455Y398256D03*
X165229Y402019D03*
X157411Y398513D03*
X169113Y398299D03*
X178031Y390023D03*
X177588Y482616D03*
X161423Y469220D03*
X153583Y461058D03*
X169297Y477094D03*
Y465283D03*
X157486Y437720D03*
Y429846D03*
X153416Y445539D03*
X169290Y417960D03*
X169297Y437720D03*
X169112Y453260D03*
X169166Y429679D03*
X153549Y429846D03*
X165621Y418066D03*
X153549Y425909D03*
X161746Y421972D03*
X177182Y467018D03*
X175477Y472360D03*
X176815Y479061D03*
X161473Y457213D03*
X165360Y477094D03*
X153549Y437720D03*
X157560Y445484D03*
X153549Y449535D03*
X174859Y469220D03*
X157322Y453385D03*
X165317Y461561D03*
X165360Y473157D03*
X161455Y453385D03*
X177763Y486293D03*
X153463Y453383D03*
X157411Y469344D03*
X161423Y477094D03*
X157486Y461346D03*
X153690Y469111D03*
X165411Y429590D03*
X175161Y434723D03*
X161423Y445598D03*
X153549Y421972D03*
X161423Y484968D03*
Y481031D03*
X157486Y473157D03*
X165360Y469220D03*
X153549Y477094D03*
X173234Y465283D03*
Y453472D03*
X174086Y484839D03*
X175150Y476294D03*
X174351Y429014D03*
X161423Y437720D03*
X153549Y433783D03*
X161363Y425780D03*
X173234Y437720D03*
X173155Y417978D03*
X153422Y441722D03*
X161423Y449430D03*
X153549Y473157D03*
X161670Y418161D03*
X176662Y418122D03*
X153201Y418097D03*
X157401Y418143D03*
X157463Y421883D03*
X157486Y425909D03*
X173458Y457178D03*
X178053Y474260D03*
X174601Y481467D03*
X165319Y453134D03*
X165353Y480812D03*
X157486Y433783D03*
X165360Y421972D03*
X153646Y457393D03*
X161294Y461561D03*
X165363Y425783D03*
X157393Y457572D03*
X165217Y457361D03*
X165355Y433382D03*
X161423Y473157D03*
X165355Y437582D03*
X165360Y445598D03*
X157411Y449556D03*
X169157Y445598D03*
X157508Y480990D03*
X165288Y449306D03*
X157486Y484968D03*
X153601Y480894D03*
X153586Y485118D03*
X161423Y433783D03*
X181414Y490281D03*
X174475Y488016D03*
X178084Y493198D03*
X157486Y488905D03*
X165360D03*
X169297Y492842D03*
X161423D03*
X159589Y817543D03*
X157422Y825918D03*
X158725Y835536D03*
X159688Y832484D03*
X159431Y838974D03*
X159688Y829234D03*
X159137Y820712D03*
X160735Y857183D03*
X154730Y847010D03*
X159688Y851564D03*
X159560Y842172D03*
X159426Y848357D03*
X651000Y467700D03*
X646163Y482677D03*
X643296Y477617D03*
X643914Y470592D03*
X648652Y470028D03*
X654990Y463513D03*
X658399Y460842D03*
X659485Y455066D03*
X666818Y452921D03*
X710645Y447266D03*
X678767Y447136D03*
X672583Y467901D03*
X667831Y479556D03*
X662166Y456914D03*
X661760Y460089D03*
X646246Y475961D03*
X646794Y472634D03*
X682915Y467823D03*
X708059Y449951D03*
X671145Y454348D03*
X658195Y464248D03*
X653351Y470098D03*
X650837Y472421D03*
X646251Y479161D03*
X675745Y448189D03*
X685815Y496140D03*
X689996Y496274D03*
X694169Y496394D03*
X698475Y496387D03*
X702670Y496148D03*
X707296Y496348D03*
X716700Y445400D03*
X742200Y472500D03*
X724300Y454000D03*
X719100Y478900D03*
X744986Y481255D03*
X749974Y477780D03*
X749628Y471196D03*
X739751Y469686D03*
X735295Y463720D03*
X738636Y457903D03*
X731780Y452531D03*
X729478Y459116D03*
X721600Y451000D03*
X719700Y485600D03*
X735191Y453967D03*
X735231Y457167D03*
X746845Y476389D03*
Y473189D03*
X717993Y451389D03*
X731751Y464398D03*
X735259Y469898D03*
X721445Y455789D03*
X726589Y460909D03*
X743520Y478297D03*
X738745Y472789D03*
X713845Y447289D03*
G54D23*
G01X74121Y451752D02*
X73136Y452737D01*
Y455114D01*
G01X72302Y452000D02*
Y454273D01*
X71257Y455318D01*
X70600D01*
G54D14*
X6614Y553544D03*
X10551Y623622D03*
X6614Y671654D03*
X10551Y741732D03*
X18425Y553544D03*
X32204D03*
X18425Y623622D03*
X32204D03*
X18425Y671654D03*
X32204D03*
X18425Y741732D03*
X32204D03*
G54D24*
G01X-755164Y-252763D02*
Y-235263D01*
G01X-746868D02*
X-755164Y-246055D01*
G01X-745558Y-252763D02*
X-751453Y-241097D01*
G01X-737883Y-252763D02*
Y-235263D01*
X-727839Y-252763D01*
Y-235263D01*
G01X-715361Y-252763D02*
X-717108Y-252471D01*
X-718636Y-251305D01*
X-719946Y-249555D01*
X-720820Y-247513D01*
X-721256Y-245180D01*
Y-242846D01*
X-720820Y-240513D01*
X-719946Y-238471D01*
X-718636Y-236722D01*
X-717108Y-235555D01*
X-715361Y-235263D01*
X-713615Y-235555D01*
X-712086Y-236722D01*
X-710776Y-238471D01*
X-709902Y-240513D01*
X-709466Y-242846D01*
Y-245180D01*
X-709902Y-247513D01*
X-710776Y-249555D01*
X-712086Y-251305D01*
X-713615Y-252471D01*
X-715361Y-252763D01*
G01X-702446D02*
X-693276Y-235263D01*
G01X-702446D02*
X-693276Y-252763D01*
G01X-658494D02*
X-667228D01*
Y-235263D01*
X-658494D01*
G01X-661988Y-243721D02*
X-667228D01*
G01X-649946Y-252763D02*
X-640776Y-235263D01*
G01X-649946D02*
X-640776Y-252763D01*
G01X-632228D02*
Y-235263D01*
X-626988D01*
X-625241Y-236138D01*
X-623931Y-238180D01*
X-623494Y-240513D01*
X-623931Y-242846D01*
X-625023Y-244596D01*
X-626988Y-245472D01*
X-632228D01*
G01X-615820Y-252763D02*
X-610361Y-235263D01*
X-604902Y-252763D01*
G01X-606868Y-246638D02*
X-613855D01*
G01X-597883Y-252763D02*
Y-235263D01*
X-587839Y-252763D01*
Y-235263D01*
G01X-580164Y-252763D02*
Y-235263D01*
X-575798D01*
X-574051Y-236138D01*
X-572741Y-237305D01*
X-571649Y-239054D01*
X-570776Y-241097D01*
X-570558Y-244013D01*
X-570776Y-246930D01*
X-571649Y-248972D01*
X-572741Y-250722D01*
X-574051Y-251888D01*
X-575798Y-252763D01*
X-580164D01*
G01X-553494D02*
X-562228D01*
Y-235263D01*
X-553494D01*
G01X-556988Y-243721D02*
X-562228D01*
G01X-544728Y-252763D02*
Y-235263D01*
X-539269D01*
X-537523Y-236138D01*
X-536431Y-237305D01*
X-535994Y-239638D01*
X-536431Y-241972D01*
X-537741Y-243430D01*
X-539269Y-244305D01*
X-544728D01*
G01X-539269D02*
X-535994Y-252763D01*
G01X-503615Y-243430D02*
X-502741Y-242555D01*
X-502086Y-241097D01*
X-501649Y-239054D01*
X-502086Y-237305D01*
X-502959Y-236138D01*
X-504488Y-235263D01*
X-510383D01*
Y-252763D01*
X-503178D01*
X-501649Y-251597D01*
X-500776Y-249846D01*
X-500339Y-247805D01*
X-500776Y-245763D01*
X-502086Y-244013D01*
X-503615Y-243430D01*
X-510383D01*
G01X-487861Y-252763D02*
X-489608Y-252471D01*
X-491136Y-251305D01*
X-492446Y-249555D01*
X-493320Y-247513D01*
X-493756Y-245180D01*
Y-242846D01*
X-493320Y-240513D01*
X-492446Y-238471D01*
X-491136Y-236722D01*
X-489608Y-235555D01*
X-487861Y-235263D01*
X-486115Y-235555D01*
X-484586Y-236722D01*
X-483276Y-238471D01*
X-482402Y-240513D01*
X-481966Y-242846D01*
Y-245180D01*
X-482402Y-247513D01*
X-483276Y-249555D01*
X-484586Y-251305D01*
X-486115Y-252471D01*
X-487861Y-252763D01*
G01X-475820D02*
X-470361Y-235263D01*
X-464902Y-252763D01*
G01X-466868Y-246638D02*
X-473855D01*
G01X-457228Y-252763D02*
Y-235263D01*
X-451769D01*
X-450023Y-236138D01*
X-448931Y-237305D01*
X-448494Y-239638D01*
X-448931Y-241972D01*
X-450241Y-243430D01*
X-451769Y-244305D01*
X-457228D01*
G01X-451769D02*
X-448494Y-252763D01*
G01X-440164D02*
Y-235263D01*
X-435798D01*
X-434051Y-236138D01*
X-432741Y-237305D01*
X-431649Y-239054D01*
X-430776Y-241097D01*
X-430558Y-244013D01*
X-430776Y-246930D01*
X-431649Y-248972D01*
X-432741Y-250722D01*
X-434051Y-251888D01*
X-435798Y-252763D01*
X-440164D01*
G01X-633538Y-207763D02*
Y-190263D01*
X-627861Y-204846D01*
X-622184Y-190263D01*
Y-207763D01*
G01X-610361D02*
X-611671Y-207471D01*
X-612981Y-206305D01*
X-613855Y-204263D01*
X-614291Y-201930D01*
X-613855Y-199596D01*
X-612981Y-197555D01*
X-611671Y-196388D01*
X-610361Y-196097D01*
X-609051Y-196388D01*
X-607741Y-197555D01*
X-606868Y-199596D01*
X-606649Y-201930D01*
X-606868Y-204263D01*
X-607741Y-206305D01*
X-609051Y-207471D01*
X-610361Y-207763D01*
G01X-588931Y-190263D02*
Y-207763D01*
G01Y-205139D02*
X-589804Y-206597D01*
X-591115Y-207471D01*
X-592643Y-207763D01*
X-594389Y-207180D01*
X-595699Y-205722D01*
X-596573Y-203972D01*
X-596791Y-201930D01*
X-596573Y-199888D01*
X-595699Y-198138D01*
X-594389Y-196680D01*
X-592643Y-196097D01*
X-591115Y-196388D01*
X-590023Y-196972D01*
X-588931Y-198138D01*
G01X-578636Y-199888D02*
X-571649D01*
X-572304Y-197846D01*
X-573396Y-196680D01*
X-574924Y-196097D01*
X-576453Y-196388D01*
X-577763Y-197263D01*
X-578636Y-199305D01*
X-579073Y-201055D01*
Y-202805D01*
X-578636Y-204555D01*
X-577544Y-206305D01*
X-576234Y-207471D01*
X-574706Y-207763D01*
X-573178Y-207180D01*
X-571649Y-205430D01*
G01X-557861Y-207763D02*
Y-190263D01*
G01X-380161Y-252763D02*
Y-235263D01*
X-382781Y-238763D01*
G01Y-252763D02*
X-377541D01*
G01X-366809Y-238180D02*
X-365499Y-236430D01*
X-363971Y-235555D01*
X-362224Y-235263D01*
X-360041Y-235846D01*
X-358513Y-237305D01*
X-358076Y-239054D01*
X-358294Y-240805D01*
X-359168Y-242263D01*
X-363534Y-245180D01*
X-365499Y-247221D01*
X-366809Y-250139D01*
X-367246Y-252763D01*
X-358076D01*
G01X-345161Y-235263D02*
X-346908Y-235846D01*
X-348218Y-237305D01*
X-349091Y-239054D01*
X-349746Y-241388D01*
X-349964Y-244013D01*
X-349746Y-246638D01*
X-349091Y-248972D01*
X-348218Y-250722D01*
X-346908Y-252180D01*
X-345161Y-252763D01*
X-343415Y-252180D01*
X-342104Y-250722D01*
X-341231Y-248972D01*
X-340576Y-246638D01*
X-340358Y-244013D01*
X-340576Y-241388D01*
X-341231Y-239054D01*
X-342104Y-237305D01*
X-343415Y-235846D01*
X-345161Y-235263D01*
G01X-327661D02*
X-329408Y-235846D01*
X-330718Y-237305D01*
X-331591Y-239054D01*
X-332246Y-241388D01*
X-332464Y-244013D01*
X-332246Y-246638D01*
X-331591Y-248972D01*
X-330718Y-250722D01*
X-329408Y-252180D01*
X-327661Y-252763D01*
X-325915Y-252180D01*
X-324604Y-250722D01*
X-323731Y-248972D01*
X-323076Y-246638D01*
X-322858Y-244013D01*
X-323076Y-241388D01*
X-323731Y-239054D01*
X-324604Y-237305D01*
X-325915Y-235846D01*
X-327661Y-235263D01*
G01X-307541Y-252763D02*
Y-235263D01*
X-315620Y-247805D01*
X-304702D01*
G01X-393278Y-207763D02*
Y-190263D01*
X-388038D01*
X-386291Y-191138D01*
X-384981Y-193180D01*
X-384544Y-195513D01*
X-384981Y-197846D01*
X-386073Y-199596D01*
X-388038Y-200472D01*
X-393278D01*
G01X-366608Y-191722D02*
X-367918Y-190846D01*
X-369446Y-190263D01*
X-371193D01*
X-373158Y-191138D01*
X-374686Y-192596D01*
X-375778Y-194347D01*
X-376651Y-197263D01*
X-376870Y-199888D01*
X-376433Y-202513D01*
X-375778Y-204263D01*
X-374468Y-206013D01*
X-372939Y-207180D01*
X-371411Y-207763D01*
X-369883D01*
X-368354Y-207180D01*
X-367044Y-206305D01*
X-365952Y-205139D01*
G01X-352165Y-198430D02*
X-351291Y-197555D01*
X-350636Y-196097D01*
X-350199Y-194054D01*
X-350636Y-192305D01*
X-351509Y-191138D01*
X-353038Y-190263D01*
X-358933D01*
Y-207763D01*
X-351728D01*
X-350199Y-206597D01*
X-349326Y-204846D01*
X-348889Y-202805D01*
X-349326Y-200763D01*
X-350636Y-199013D01*
X-352165Y-198430D01*
X-358933D01*
G01X-342961Y-213596D02*
X-329861D01*
G01X-323933Y-207763D02*
Y-190263D01*
X-313889Y-207763D01*
Y-190263D01*
G01X-301411Y-207763D02*
X-303158Y-207471D01*
X-304686Y-206305D01*
X-305996Y-204555D01*
X-306870Y-202513D01*
X-307306Y-200180D01*
Y-197846D01*
X-306870Y-195513D01*
X-305996Y-193471D01*
X-304686Y-191722D01*
X-303158Y-190555D01*
X-301411Y-190263D01*
X-299665Y-190555D01*
X-298136Y-191722D01*
X-296826Y-193471D01*
X-295952Y-195513D01*
X-295516Y-197846D01*
Y-200180D01*
X-295952Y-202513D01*
X-296826Y-204555D01*
X-298136Y-206305D01*
X-299665Y-207471D01*
X-301411Y-207763D01*
G01X-218861Y-252763D02*
Y-235263D01*
X-221481Y-238763D01*
G01Y-252763D02*
X-216241D01*
G01X-250570Y-190263D02*
X-245111Y-207763D01*
X-239652Y-190263D01*
G01X-223244Y-207763D02*
X-231978D01*
Y-190263D01*
X-223244D01*
G01X-226738Y-198721D02*
X-231978D01*
G01X-214478Y-207763D02*
Y-190263D01*
X-209019D01*
X-207273Y-191138D01*
X-206181Y-192305D01*
X-205744Y-194638D01*
X-206181Y-196972D01*
X-207491Y-198430D01*
X-209019Y-199305D01*
X-214478D01*
G01X-209019D02*
X-205744Y-207763D01*
G01X-192611Y-208346D02*
X-193048Y-208055D01*
Y-207471D01*
X-192611Y-207180D01*
X-192174Y-207471D01*
Y-208055D01*
X-192611Y-208346D01*
G01X-64544Y-235263D02*
Y-252763D01*
X-73278D01*
G01X-82263Y-245472D02*
X-83791Y-243430D01*
X-85101Y-242263D01*
X-86848Y-241680D01*
X-88376Y-242263D01*
X-89468Y-243430D01*
X-90341Y-245180D01*
X-90559Y-247221D01*
X-90341Y-248972D01*
X-89468Y-250722D01*
X-88157Y-252180D01*
X-86629Y-252763D01*
X-84883Y-252180D01*
X-83354Y-250430D01*
X-82481Y-247805D01*
X-82263Y-244888D01*
X-82699Y-241097D01*
X-83354Y-239054D01*
X-84446Y-237013D01*
X-85974Y-235555D01*
X-87503Y-235263D01*
X-89031Y-235846D01*
X-90123Y-237305D01*
G01X-125778Y-190263D02*
Y-207763D01*
X-117044D01*
G01X-99981D02*
Y-196097D01*
G01Y-198138D02*
X-100854Y-196972D01*
X-102165Y-196388D01*
X-103693Y-196097D01*
X-105221Y-196680D01*
X-106531Y-197846D01*
X-107405Y-199596D01*
X-107841Y-201930D01*
X-107405Y-204263D01*
X-106531Y-206013D01*
X-105221Y-207180D01*
X-103693Y-207763D01*
X-102165Y-207471D01*
X-100854Y-206597D01*
X-99981Y-205430D01*
G01X-90996Y-213013D02*
X-89686Y-213596D01*
X-87939Y-213013D01*
X-86848Y-211847D01*
X-85974Y-210388D01*
X-84665Y-205722D01*
X-81826Y-196097D01*
G01X-88813D02*
X-84665Y-205722D01*
G01X-72186Y-199888D02*
X-65199D01*
X-65854Y-197846D01*
X-66946Y-196680D01*
X-68474Y-196097D01*
X-70003Y-196388D01*
X-71313Y-197263D01*
X-72186Y-199305D01*
X-72623Y-201055D01*
Y-202805D01*
X-72186Y-204555D01*
X-71094Y-206305D01*
X-69784Y-207471D01*
X-68256Y-207763D01*
X-66728Y-207180D01*
X-65199Y-205430D01*
G01X-54468Y-207763D02*
Y-196097D01*
G01Y-198430D02*
X-53376Y-197263D01*
X-52284Y-196388D01*
X-50756Y-196097D01*
X-49665Y-196388D01*
X-48354Y-197263D01*
G01X-37186Y-205722D02*
X-36094Y-206888D01*
X-34566Y-207763D01*
X-33256D01*
X-31946Y-207180D01*
X-31073Y-206305D01*
X-30636Y-205139D01*
X-30854Y-203388D01*
X-31728Y-202513D01*
X-35658Y-200763D01*
X-36531Y-198721D01*
X-36094Y-197263D01*
X-35221Y-196388D01*
X-33911Y-196097D01*
X-32601Y-196388D01*
X-31291Y-197263D01*
G01X51772Y-235263D02*
Y-252763D01*
X60506D01*
G01X68836Y-235263D02*
Y-247805D01*
X69709Y-250430D01*
X71456Y-252180D01*
X73639Y-252763D01*
X75822Y-252180D01*
X77569Y-250430D01*
X78442Y-247805D01*
Y-235263D01*
G01X95942Y-236722D02*
X94632Y-235846D01*
X93104Y-235263D01*
X91357D01*
X89392Y-236138D01*
X87864Y-237596D01*
X86772Y-239347D01*
X85899Y-242263D01*
X85680Y-244888D01*
X86117Y-247513D01*
X86772Y-249263D01*
X88082Y-251013D01*
X89611Y-252180D01*
X91139Y-252763D01*
X92667D01*
X94196Y-252180D01*
X95506Y-251305D01*
X96598Y-250139D01*
G01X103836Y-252763D02*
Y-235263D01*
G01X112132D02*
X103836Y-246055D01*
G01X113442Y-252763D02*
X107547Y-241097D01*
G01X126139Y-252763D02*
Y-244888D01*
X121772Y-235263D01*
G01X130506D02*
X126139Y-244888D01*
G01X25086Y-207763D02*
Y-190263D01*
X29452D01*
X31199Y-191138D01*
X32509Y-192305D01*
X33601Y-194054D01*
X34474Y-196097D01*
X34692Y-199013D01*
X34474Y-201930D01*
X33601Y-203972D01*
X32509Y-205722D01*
X31199Y-206888D01*
X29452Y-207763D01*
X25086D01*
G01X44114Y-199888D02*
X51101D01*
X50446Y-197846D01*
X49354Y-196680D01*
X47826Y-196097D01*
X46297Y-196388D01*
X44987Y-197263D01*
X44114Y-199305D01*
X43677Y-201055D01*
Y-202805D01*
X44114Y-204555D01*
X45206Y-206305D01*
X46516Y-207471D01*
X48044Y-207763D01*
X49572Y-207180D01*
X51101Y-205430D01*
G01X61614Y-205722D02*
X62706Y-206888D01*
X64234Y-207763D01*
X65544D01*
X66854Y-207180D01*
X67727Y-206305D01*
X68164Y-205139D01*
X67946Y-203388D01*
X67072Y-202513D01*
X63142Y-200763D01*
X62269Y-198721D01*
X62706Y-197263D01*
X63579Y-196388D01*
X64889Y-196097D01*
X66199Y-196388D01*
X67509Y-197263D01*
G01X82389Y-196097D02*
Y-207763D01*
G01Y-191430D02*
X81952Y-191138D01*
Y-190555D01*
X82389Y-190263D01*
X82826Y-190555D01*
Y-191138D01*
X82389Y-191430D01*
G01X96832Y-212138D02*
X98361Y-213305D01*
X100107Y-213596D01*
X101635Y-213305D01*
X102946Y-211847D01*
X103819Y-209805D01*
Y-196097D01*
G01Y-198430D02*
X102946Y-197263D01*
X101635Y-196388D01*
X100107Y-196097D01*
X98361Y-196680D01*
X97269Y-197846D01*
X96395Y-199888D01*
X95959Y-201930D01*
X96177Y-203680D01*
X97051Y-205722D01*
X98361Y-207180D01*
X100107Y-207763D01*
X101417Y-207471D01*
X102946Y-206305D01*
X103819Y-205139D01*
G01X113677Y-207763D02*
Y-196097D01*
G01Y-199013D02*
X114551Y-197555D01*
X115861Y-196388D01*
X117607Y-196097D01*
X119135Y-196388D01*
X120446Y-197555D01*
X121101Y-199596D01*
Y-207763D01*
G01X131614Y-199888D02*
X138601D01*
X137946Y-197846D01*
X136854Y-196680D01*
X135326Y-196097D01*
X133797Y-196388D01*
X132487Y-197263D01*
X131614Y-199305D01*
X131177Y-201055D01*
Y-202805D01*
X131614Y-204555D01*
X132706Y-206305D01*
X134016Y-207471D01*
X135544Y-207763D01*
X137072Y-207180D01*
X138601Y-205430D01*
G01X149332Y-207763D02*
Y-196097D01*
G01Y-198430D02*
X150424Y-197263D01*
X151516Y-196388D01*
X153044Y-196097D01*
X154135Y-196388D01*
X155446Y-197263D01*
G01X196089Y-252763D02*
Y-235263D01*
X193469Y-238763D01*
G01Y-252763D02*
X198709D01*
G01X213589Y-235263D02*
X211842Y-235846D01*
X210532Y-237305D01*
X209659Y-239054D01*
X209004Y-241388D01*
X208786Y-244013D01*
X209004Y-246638D01*
X209659Y-248972D01*
X210532Y-250722D01*
X211842Y-252180D01*
X213589Y-252763D01*
X215335Y-252180D01*
X216646Y-250722D01*
X217519Y-248972D01*
X218174Y-246638D01*
X218392Y-244013D01*
X218174Y-241388D01*
X217519Y-239054D01*
X216646Y-237305D01*
X215335Y-235846D01*
X213589Y-235263D01*
G01X227159Y-253346D02*
X235019Y-235263D01*
G01X248589Y-252763D02*
Y-235263D01*
X245969Y-238763D01*
G01Y-252763D02*
X251209D01*
G01X261941Y-245472D02*
X263469Y-243430D01*
X264779Y-242263D01*
X266526Y-241680D01*
X268054Y-242263D01*
X269146Y-243430D01*
X270019Y-245180D01*
X270237Y-247221D01*
X270019Y-248972D01*
X269146Y-250722D01*
X267835Y-252180D01*
X266307Y-252763D01*
X264561Y-252180D01*
X263032Y-250430D01*
X262159Y-247805D01*
X261941Y-244888D01*
X262377Y-241097D01*
X263032Y-239054D01*
X264124Y-237013D01*
X265652Y-235555D01*
X267181Y-235263D01*
X268709Y-235846D01*
X269801Y-237305D01*
G01X279659Y-253346D02*
X287519Y-235263D01*
G01X296941Y-238180D02*
X298251Y-236430D01*
X299779Y-235555D01*
X301526Y-235263D01*
X303709Y-235846D01*
X305237Y-237305D01*
X305674Y-239054D01*
X305456Y-240805D01*
X304582Y-242263D01*
X300216Y-245180D01*
X298251Y-247221D01*
X296941Y-250139D01*
X296504Y-252763D01*
X305674D01*
G01X318589Y-235263D02*
X316842Y-235846D01*
X315532Y-237305D01*
X314659Y-239054D01*
X314004Y-241388D01*
X313786Y-244013D01*
X314004Y-246638D01*
X314659Y-248972D01*
X315532Y-250722D01*
X316842Y-252180D01*
X318589Y-252763D01*
X320335Y-252180D01*
X321646Y-250722D01*
X322519Y-248972D01*
X323174Y-246638D01*
X323392Y-244013D01*
X323174Y-241388D01*
X322519Y-239054D01*
X321646Y-237305D01*
X320335Y-235846D01*
X318589Y-235263D01*
G01X336089Y-252763D02*
Y-235263D01*
X333469Y-238763D01*
G01Y-252763D02*
X338709D01*
G01X349441Y-238180D02*
X350751Y-236430D01*
X352279Y-235555D01*
X354026Y-235263D01*
X356209Y-235846D01*
X357737Y-237305D01*
X358174Y-239054D01*
X357956Y-240805D01*
X357082Y-242263D01*
X352716Y-245180D01*
X350751Y-247221D01*
X349441Y-250139D01*
X349004Y-252763D01*
X358174D01*
G01X243786Y-207763D02*
Y-190263D01*
X248152D01*
X249899Y-191138D01*
X251209Y-192305D01*
X252301Y-194054D01*
X253174Y-196097D01*
X253392Y-199013D01*
X253174Y-201930D01*
X252301Y-203972D01*
X251209Y-205722D01*
X249899Y-206888D01*
X248152Y-207763D01*
X243786D01*
G01X270019D02*
Y-196097D01*
G01Y-198138D02*
X269146Y-196972D01*
X267835Y-196388D01*
X266307Y-196097D01*
X264779Y-196680D01*
X263469Y-197846D01*
X262595Y-199596D01*
X262159Y-201930D01*
X262595Y-204263D01*
X263469Y-206013D01*
X264779Y-207180D01*
X266307Y-207763D01*
X267835Y-207471D01*
X269146Y-206597D01*
X270019Y-205430D01*
G01X283589Y-190263D02*
Y-207763D01*
G01X280532Y-196097D02*
X286646D01*
G01X297814Y-199888D02*
X304801D01*
X304146Y-197846D01*
X303054Y-196680D01*
X301526Y-196097D01*
X299997Y-196388D01*
X298687Y-197263D01*
X297814Y-199305D01*
X297377Y-201055D01*
Y-202805D01*
X297814Y-204555D01*
X298906Y-206305D01*
X300216Y-207471D01*
X301744Y-207763D01*
X303272Y-207180D01*
X304801Y-205430D01*
G01X90359Y469275D02*
X88862Y467778D01*
Y459938D01*
X90600Y458200D01*
X92400D01*
X96500Y454100D01*
X99700D01*
X101083Y455483D01*
X111009D01*
X118000Y462474D01*
Y474300D01*
X124190Y480490D01*
Y493290D01*
X132500Y501600D01*
X195400D01*
X202100Y494900D01*
X223800D01*
X225700Y496800D01*
G01X98682Y461441D02*
X100823Y459300D01*
X108100D01*
X115975Y467175D01*
Y475475D01*
X119400Y478900D01*
Y486000D01*
X121900Y488500D01*
Y495500D01*
X130100Y503700D01*
X196270D01*
X202970Y497000D01*
X222300D01*
X224200Y498900D01*
X228500D01*
G54D15*
X22980Y59055D03*
X30854D03*
X22980Y106299D03*
Y98425D03*
Y90551D03*
Y82677D03*
Y74803D03*
Y66929D03*
X30854Y106299D03*
Y98425D03*
Y90551D03*
Y82677D03*
Y74803D03*
Y66929D03*
X41142Y135669D03*
Y155669D03*
Y145669D03*
X26181Y537559D03*
Y527559D03*
Y517559D03*
X41142Y655669D03*
Y645669D03*
Y635669D03*
Y763780D03*
Y753780D03*
Y773780D03*
G54D25*
G01X11964Y421332D02*
X11220D01*
X5026Y415138D01*
Y330710D01*
X19758Y315978D01*
X23098D01*
X24166Y314910D01*
Y311570D01*
X53496Y282240D01*
X56191D01*
X57698Y280733D01*
Y280573D01*
X58814Y279457D01*
Y277002D01*
X70176Y265640D01*
Y265145D01*
X71245Y264076D01*
X71740D01*
X79583Y256233D01*
X113638D01*
X120490Y263085D01*
X125533D01*
X130567Y258051D01*
G01X6944Y414616D02*
Y414398D01*
X6676Y414130D01*
Y331394D01*
X7846Y330224D01*
X8482D01*
X9413Y331155D01*
X10049D01*
X10686Y330518D01*
Y329882D01*
X9755Y328951D01*
Y328315D01*
X10392Y327678D01*
X11028D01*
X11959Y328609D01*
X12595D01*
X13232Y327972D01*
Y327336D01*
X12301Y326405D01*
Y325769D01*
X12938Y325132D01*
X13574D01*
X14505Y326063D01*
X15141D01*
X15778Y325426D01*
Y324790D01*
X14847Y323859D01*
Y323223D01*
X15484Y322586D01*
X16120D01*
X17051Y323517D01*
X17687D01*
X18324Y322880D01*
Y322244D01*
X17393Y321313D01*
Y320677D01*
X20442Y317628D01*
X24374D01*
X27776Y314226D01*
Y313590D01*
X26455Y312269D01*
Y311633D01*
X27092Y310996D01*
X27728D01*
X29049Y312317D01*
X29685D01*
X30322Y311680D01*
Y311044D01*
X29001Y309723D01*
Y309087D01*
X29638Y308450D01*
X30274D01*
X31595Y309771D01*
X32231D01*
X32868Y309134D01*
Y308498D01*
X31547Y307177D01*
Y306541D01*
X32184Y305904D01*
X32820D01*
X34141Y307225D01*
X34777D01*
X35414Y306588D01*
Y305952D01*
X34093Y304631D01*
Y303995D01*
X34730Y303358D01*
X35366D01*
X36687Y304679D01*
X37323D01*
X37960Y304042D01*
Y303406D01*
X36639Y302085D01*
Y301449D01*
X37276Y300812D01*
X37912D01*
X39233Y302133D01*
X39869D01*
X40506Y301496D01*
Y300860D01*
X39185Y299539D01*
Y298903D01*
X39822Y298266D01*
X40458D01*
X41779Y299587D01*
X42415D01*
X46084Y295918D01*
Y291986D01*
X47254Y290816D01*
X47890D01*
X48651Y291577D01*
X49286D01*
X49923Y290940D01*
Y290304D01*
X49163Y289543D01*
Y288907D01*
X49800Y288270D01*
X50436D01*
X51197Y289031D01*
X51832D01*
X52469Y288394D01*
Y287758D01*
X51709Y286997D01*
Y286361D01*
X54180Y283890D01*
X56876D01*
X57611Y283155D01*
X60280D01*
X61348Y282087D01*
Y276802D01*
X70202Y267948D01*
X72700D01*
X74514Y266134D01*
Y263637D01*
X75770Y262380D01*
X80267Y257883D01*
X104399D01*
X106381Y259865D01*
G01X126611Y258265D02*
X124668Y256322D01*
X116101D01*
X114362Y254583D01*
X78404D01*
X68526Y264461D01*
Y264956D01*
X55060Y278422D01*
X54811D01*
X3376Y329857D01*
Y434591D01*
X5629Y436844D01*
X6855D01*
G01X101242Y265901D02*
Y263209D01*
X99216Y261183D01*
X93898D01*
X93448Y261633D01*
Y262891D01*
X94604Y264047D01*
X94808D01*
X95876Y265115D01*
Y266645D01*
X94736Y267785D01*
X86223D01*
X79510Y274498D01*
Y280642D01*
X66417Y293735D01*
Y302849D01*
X58400Y310866D01*
X57132D01*
X17652Y350346D01*
Y380113D01*
X17648Y380121D01*
X17607Y380162D01*
X14926Y382853D01*
Y408040D01*
X16382Y409496D01*
Y420012D01*
X17149Y420779D01*
Y427632D01*
X13777Y431004D01*
X12347D01*
X11337Y429994D01*
Y427968D01*
X10962Y427593D01*
X5439D01*
X5026Y428006D01*
Y433219D01*
X5439Y433632D01*
X14206D01*
G01X43980Y86200D02*
X45080Y87300D01*
X67550D01*
X68000Y87750D01*
G01X79600Y91500D02*
X71300D01*
X69800Y93000D01*
X52300D01*
X51800Y93500D01*
G01X51900Y89900D02*
X59500D01*
X60900Y91300D01*
X69000D01*
X70500Y89800D01*
X75400D01*
X79500Y85700D01*
G01X373496Y140021D02*
Y141894D01*
X350740Y164650D01*
X88284D01*
X76250Y152616D01*
Y148850D01*
G01X70675Y145000D02*
Y149375D01*
X88400Y167100D01*
X117300D01*
X124575Y174375D01*
Y174381D01*
X125819Y175625D01*
X125825D01*
X150500Y200300D01*
X322100D01*
X395000Y273200D01*
X727300D01*
G01X70636Y272953D02*
X68852Y274737D01*
Y276917D01*
X58455Y287314D01*
X58340D01*
X57245Y288409D01*
Y289413D01*
X56177Y290481D01*
X52716D01*
X48485Y294712D01*
Y299377D01*
X47417Y300445D01*
X44280D01*
X10325Y334400D01*
X9243D01*
G01X14422Y411528D02*
Y409870D01*
X13276Y408724D01*
Y382170D01*
X14561Y380880D01*
X15998Y379438D01*
Y349666D01*
X56448Y309216D01*
X57716D01*
X64743Y302189D01*
Y293075D01*
X77859Y279959D01*
Y279173D01*
X77860Y279172D01*
Y278592D01*
X77859Y278591D01*
Y273815D01*
X87016Y264658D01*
X87263D01*
G01X14657Y416838D02*
X12340Y414521D01*
Y410216D01*
X11626Y409502D01*
Y381417D01*
X12013Y381030D01*
X14348Y378688D01*
Y346074D01*
X15518Y344904D01*
X16154D01*
X16972Y345722D01*
X17608D01*
X18245Y345085D01*
Y344449D01*
X17427Y343631D01*
Y342995D01*
X18064Y342358D01*
X18700D01*
X19518Y343176D01*
X20154D01*
X20791Y342539D01*
Y341903D01*
X19973Y341085D01*
Y340449D01*
X20610Y339812D01*
X21246D01*
X22064Y340630D01*
X22700D01*
X23337Y339993D01*
Y339357D01*
X22519Y338539D01*
Y337903D01*
X23156Y337266D01*
X23792D01*
X24610Y338084D01*
X25246D01*
X25883Y337447D01*
Y336811D01*
X25065Y335993D01*
Y335357D01*
X25702Y334720D01*
X26338D01*
X27156Y335538D01*
X27792D01*
X28429Y334901D01*
Y334265D01*
X27611Y333447D01*
Y332811D01*
X28248Y332174D01*
X28884D01*
X29702Y332992D01*
X30338D01*
X30975Y332355D01*
Y331719D01*
X30157Y330901D01*
Y330265D01*
X30794Y329628D01*
X31430D01*
X32248Y330446D01*
X32884D01*
X33521Y329809D01*
Y329173D01*
X32703Y328355D01*
Y327719D01*
X33340Y327082D01*
X33976D01*
X34794Y327900D01*
X35430D01*
X37098Y326232D01*
Y325596D01*
X33813Y322311D01*
Y321675D01*
X34450Y321038D01*
X35086D01*
X38371Y324323D01*
X39007D01*
X39644Y323686D01*
Y323050D01*
X36359Y319765D01*
Y319129D01*
X36996Y318492D01*
X37632D01*
X40917Y321777D01*
X41553D01*
X42190Y321140D01*
Y320504D01*
X38905Y317219D01*
Y316583D01*
X39542Y315946D01*
X40178D01*
X43463Y319231D01*
X44099D01*
X44736Y318594D01*
Y317958D01*
X41451Y314673D01*
Y314037D01*
X42088Y313400D01*
X42724D01*
X46009Y316685D01*
X46645D01*
X47282Y316048D01*
Y315412D01*
X43997Y312127D01*
Y311491D01*
X44634Y310854D01*
X45270D01*
X48555Y314139D01*
X49191D01*
X49828Y313502D01*
Y312866D01*
X46543Y309581D01*
Y308945D01*
X47180Y308308D01*
X47816D01*
X51101Y311593D01*
X51737D01*
X55764Y307566D01*
X57032D01*
X63093Y301505D01*
Y292391D01*
X76209Y279275D01*
Y273131D01*
X86507Y262833D01*
X88019D01*
X90652Y265466D01*
Y265960D01*
G01X94051Y265872D02*
X93788Y265609D01*
Y265565D01*
X89406Y261183D01*
X85823D01*
X74559Y272447D01*
Y278591D01*
X61443Y291707D01*
Y300804D01*
X61141Y301106D01*
Y301123D01*
X60073Y302191D01*
X60056D01*
X56331Y305916D01*
X55080D01*
X54946Y306050D01*
X47102D01*
X31158Y321994D01*
Y322630D01*
X32871Y324343D01*
Y324979D01*
X32234Y325616D01*
X31598D01*
X29885Y323903D01*
X29249D01*
X28612Y324540D01*
Y325176D01*
X30325Y326889D01*
Y327525D01*
X29688Y328162D01*
X29052D01*
X27339Y326449D01*
X26703D01*
X26066Y327086D01*
Y327722D01*
X27779Y329435D01*
Y330071D01*
X27142Y330708D01*
X26506D01*
X24793Y328995D01*
X24157D01*
X23520Y329632D01*
Y330268D01*
X25233Y331981D01*
Y332617D01*
X24596Y333254D01*
X23960D01*
X22247Y331541D01*
X21611D01*
X20974Y332178D01*
Y332814D01*
X22687Y334527D01*
Y335163D01*
X22050Y335800D01*
X21414D01*
X19701Y334087D01*
X19065D01*
X18428Y334724D01*
Y335360D01*
X20141Y337073D01*
Y337709D01*
X19504Y338346D01*
X18868D01*
X17155Y336633D01*
X16519D01*
X15882Y337270D01*
Y337906D01*
X17595Y339619D01*
Y340255D01*
X16958Y340892D01*
X16322D01*
X14609Y339179D01*
X13973D01*
X13336Y339816D01*
Y340452D01*
X15049Y342165D01*
Y342801D01*
X12698Y345152D01*
Y378004D01*
X10363Y380346D01*
X9976Y380733D01*
Y410434D01*
X10615Y411073D01*
G01X103003Y260260D02*
X102276Y259533D01*
X85139D01*
X72909Y271763D01*
Y277907D01*
X69118Y281698D01*
X68482D01*
X67802Y281018D01*
X67166D01*
X66529Y281655D01*
Y282291D01*
X67209Y282971D01*
Y283607D01*
X66572Y284244D01*
X65936D01*
X65256Y283564D01*
X64620D01*
X63983Y284201D01*
Y284837D01*
X64663Y285517D01*
Y286153D01*
X64026Y286790D01*
X63390D01*
X62710Y286110D01*
X62074D01*
X61437Y286747D01*
Y287383D01*
X62117Y288063D01*
Y288699D01*
X56300Y294516D01*
X55664D01*
X53700Y292552D01*
X53065D01*
X52428Y293190D01*
Y293826D01*
X54391Y295789D01*
Y296425D01*
X53754Y297062D01*
X53118D01*
X51420Y295364D01*
X50785D01*
X50148Y296002D01*
Y296638D01*
X51845Y298335D01*
Y298971D01*
X39119Y311697D01*
X38483D01*
X37241Y310455D01*
X36605D01*
X35968Y311092D01*
Y311728D01*
X37210Y312970D01*
Y313606D01*
X36573Y314243D01*
X35937D01*
X34695Y313001D01*
X34059D01*
X33422Y313638D01*
Y314274D01*
X34664Y315516D01*
Y316152D01*
X34027Y316789D01*
X33391D01*
X32149Y315547D01*
X31513D01*
X30876Y316184D01*
Y316820D01*
X32118Y318062D01*
Y318698D01*
X31481Y319335D01*
X30845D01*
X29603Y318093D01*
X28967D01*
X28330Y318730D01*
Y319366D01*
X29572Y320608D01*
Y321244D01*
X28935Y321881D01*
X28299D01*
X27057Y320639D01*
X26421D01*
X25784Y321276D01*
Y321912D01*
X27026Y323154D01*
Y323790D01*
X26389Y324427D01*
X25753D01*
X24511Y323185D01*
X23875D01*
X23238Y323822D01*
Y324458D01*
X24480Y325700D01*
Y326336D01*
X23843Y326973D01*
X23207D01*
X21965Y325731D01*
X21329D01*
X20692Y326368D01*
Y327004D01*
X21934Y328246D01*
Y328882D01*
X21297Y329519D01*
X20661D01*
X19419Y328277D01*
X18783D01*
X18146Y328914D01*
Y329550D01*
X19388Y330792D01*
Y331428D01*
X18751Y332065D01*
X18115D01*
X16873Y330823D01*
X16237D01*
X15600Y331460D01*
Y332096D01*
X16842Y333338D01*
Y333974D01*
X15546Y335270D01*
X14910D01*
X13732Y334092D01*
X13096D01*
X12459Y334729D01*
Y335365D01*
X13637Y336543D01*
Y337179D01*
X11047Y339769D01*
Y377318D01*
X8326Y380047D01*
Y411149D01*
X9039Y411862D01*
Y415003D01*
X13689Y419653D01*
Y426469D01*
X13062Y427096D01*
Y429279D01*
G01X497279Y382551D02*
X496335Y381607D01*
Y381306D01*
X320329Y205300D01*
X114328D01*
X105228Y214400D01*
X84153D01*
X76019Y222534D01*
G01X119603Y285731D02*
X118390Y286944D01*
Y291644D01*
X114621Y295413D01*
X98270D01*
X96642Y297041D01*
Y310240D01*
X37964Y368918D01*
Y387819D01*
X35243Y390540D01*
Y400032D01*
X33722Y401553D01*
Y401639D01*
G01X9243Y334400D02*
X8789Y334854D01*
Y376072D01*
G01X35738Y406956D02*
Y401871D01*
X36893Y400716D01*
Y391224D01*
X39614Y388503D01*
Y369602D01*
X40784Y368432D01*
X41420D01*
X44599Y371611D01*
X45235D01*
X45872Y370974D01*
Y370338D01*
X42693Y367159D01*
Y366523D01*
X43330Y365886D01*
X43966D01*
X47145Y369065D01*
X47781D01*
X48418Y368428D01*
Y367792D01*
X45239Y364613D01*
Y363977D01*
X45876Y363340D01*
X46512D01*
X49691Y366519D01*
X50327D01*
X50964Y365882D01*
Y365246D01*
X47785Y362067D01*
Y361431D01*
X48422Y360794D01*
X49058D01*
X52237Y363973D01*
X52873D01*
X53510Y363336D01*
Y362700D01*
X50331Y359521D01*
Y358885D01*
X50968Y358248D01*
X51604D01*
X54783Y361427D01*
X55419D01*
X56056Y360790D01*
Y360154D01*
X52877Y356975D01*
Y356339D01*
X54047Y355169D01*
X54683D01*
X57699Y358185D01*
X58335D01*
X58972Y357548D01*
Y356912D01*
X55956Y353896D01*
Y353260D01*
X98292Y310924D01*
Y297725D01*
X98954Y297063D01*
X100604D01*
X101054Y297513D01*
Y307638D01*
X101504Y308088D01*
X102404D01*
X102854Y307638D01*
Y297513D01*
X103304Y297063D01*
X104204D01*
X104654Y297513D01*
Y307638D01*
X105104Y308088D01*
X106004D01*
X106454Y307638D01*
Y297513D01*
X106904Y297063D01*
X115305D01*
X124478Y287890D01*
Y286240D01*
X124028Y285790D01*
X121879D01*
X121429Y285340D01*
Y284440D01*
X121879Y283990D01*
X124028D01*
X124478Y283540D01*
Y280855D01*
G01X26551Y394546D02*
Y387562D01*
X29633Y384480D01*
Y365270D01*
X66918Y327985D01*
Y318898D01*
X77967Y307849D01*
Y298524D01*
X91060Y285431D01*
Y281386D01*
X93111Y279335D01*
X94872D01*
X95146Y279609D01*
G01X30232Y416556D02*
Y420876D01*
X29782Y421326D01*
X23915D01*
X23473Y420884D01*
Y418700D01*
X23923Y418250D01*
X26613D01*
X27063Y417800D01*
Y414883D01*
X26613Y414433D01*
X25697D01*
X25247Y413983D01*
Y412333D01*
X25697Y411883D01*
X26597D01*
X27047Y411433D01*
Y410533D01*
X26597Y410083D01*
X25697D01*
X25247Y409633D01*
Y408733D01*
X25697Y408283D01*
X26597D01*
X27047Y407833D01*
Y406933D01*
X26597Y406483D01*
X25697D01*
X25247Y406033D01*
Y405133D01*
X25697Y404683D01*
X26597D01*
X27047Y404233D01*
Y403333D01*
X26597Y402883D01*
X25697D01*
X25247Y402433D01*
Y397565D01*
X24826Y397144D01*
Y386953D01*
X27983Y383796D01*
Y364133D01*
X36168Y355948D01*
Y355312D01*
X33824Y352968D01*
Y352332D01*
X34461Y351694D01*
X35096D01*
X37441Y354039D01*
X38077D01*
X38714Y353402D01*
Y352766D01*
X35044Y349096D01*
Y348460D01*
X35681Y347822D01*
X36316D01*
X39987Y351493D01*
X40623D01*
X41260Y350856D01*
Y350220D01*
X37606Y346566D01*
Y345930D01*
X38243Y345292D01*
X38878D01*
X42533Y348947D01*
X43169D01*
X43806Y348310D01*
Y347674D01*
X40094Y343962D01*
Y343387D01*
X40793Y342688D01*
X41366D01*
X45079Y346401D01*
X45715D01*
X46352Y345764D01*
Y345128D01*
X42698Y341474D01*
Y340838D01*
X43335Y340200D01*
X43970D01*
X47625Y343855D01*
X48261D01*
X48898Y343218D01*
Y342582D01*
X45218Y338902D01*
Y338267D01*
X45856Y337630D01*
X46492D01*
X50171Y341309D01*
X50807D01*
X51444Y340672D01*
Y340036D01*
X47823Y336415D01*
Y335779D01*
X48460Y335142D01*
X49096D01*
X52717Y338763D01*
X53353D01*
X57950Y334166D01*
X58403D01*
X65268Y327301D01*
Y318214D01*
X76317Y307165D01*
Y297840D01*
X77706Y296451D01*
Y296450D01*
X89410Y284746D01*
Y278709D01*
X90434Y277685D01*
X96622D01*
X98546Y279609D01*
G01X23922Y415548D02*
X23597Y415223D01*
Y398249D01*
X23176Y397828D01*
Y386269D01*
X26333Y383112D01*
Y363449D01*
X32098Y357684D01*
Y349049D01*
X48631Y332516D01*
X57719D01*
X63618Y326617D01*
Y317530D01*
X74667Y306481D01*
Y297155D01*
X76056Y295767D01*
Y295766D01*
X87760Y284062D01*
Y278025D01*
X89750Y276035D01*
X97852D01*
X99098Y277281D01*
X103086D01*
X104413Y278608D01*
G01X35994Y410146D02*
X38543Y407597D01*
Y391908D01*
X41264Y389187D01*
Y377841D01*
X42841Y376264D01*
X45725D01*
X46189Y375800D01*
Y372993D01*
X62261Y356921D01*
Y356285D01*
X59082Y353106D01*
Y352470D01*
X59719Y351833D01*
X60355D01*
X63534Y355012D01*
X64170D01*
X64807Y354375D01*
Y353739D01*
X61628Y350560D01*
Y349924D01*
X62265Y349287D01*
X62901D01*
X66080Y352466D01*
X66716D01*
X67353Y351829D01*
Y351193D01*
X64174Y348014D01*
Y347376D01*
X99957Y311593D01*
X102985D01*
X103362Y311970D01*
X107212D01*
X109952Y309230D01*
Y308594D01*
X108226Y306866D01*
Y306230D01*
X108863Y305594D01*
X109500D01*
X111225Y307321D01*
X111861D01*
X112498Y306684D01*
Y306048D01*
X108181Y301727D01*
Y301092D01*
X108819Y300455D01*
X109455D01*
X113771Y304775D01*
X114407D01*
X115044Y304138D01*
Y303502D01*
X111688Y300144D01*
Y299508D01*
X112326Y298871D01*
X112962D01*
X116317Y302229D01*
X116953D01*
X117590Y301592D01*
Y300956D01*
X116381Y299746D01*
Y299110D01*
X117018Y298473D01*
X117654D01*
X118863Y299683D01*
X119499D01*
X120136Y299046D01*
Y298410D01*
X118927Y297200D01*
Y296564D01*
X119564Y295927D01*
X120200D01*
X121409Y297137D01*
X122045D01*
X122682Y296500D01*
Y295864D01*
X121473Y294654D01*
Y294018D01*
X122110Y293381D01*
X122746D01*
X123955Y294591D01*
X124591D01*
X125228Y293954D01*
Y293318D01*
X124019Y292108D01*
Y291472D01*
X124656Y290835D01*
X125292D01*
X126501Y292045D01*
X127137D01*
X128349Y290833D01*
Y289183D01*
X127899Y288733D01*
X126559D01*
X126128Y288302D01*
Y287364D01*
X126559Y286933D01*
X127899D01*
X128349Y286483D01*
Y285583D01*
X127899Y285133D01*
X127057D01*
X126607Y284683D01*
Y283783D01*
X127057Y283333D01*
X127899D01*
X128349Y282883D01*
Y281983D01*
X127899Y281533D01*
X127306D01*
X126856Y281083D01*
Y280183D01*
X127306Y279733D01*
X127899D01*
X128349Y279283D01*
Y262850D01*
X132651Y258548D01*
Y255357D01*
G01X124933Y270414D02*
X126699Y272180D01*
Y276052D01*
X121218Y281533D01*
Y281540D01*
X119158Y283600D01*
X119151D01*
X116740Y286011D01*
Y290960D01*
X113937Y293763D01*
X97389D01*
X94992Y296160D01*
Y309556D01*
X36314Y368234D01*
Y387135D01*
X33476Y389973D01*
Y397063D01*
X31997Y398542D01*
Y407357D01*
X32141Y407501D01*
G01X31808Y410684D02*
X30347Y409223D01*
Y397858D01*
X31826Y396379D01*
Y389289D01*
X34664Y386451D01*
Y367241D01*
X75921Y325984D01*
Y325348D01*
X72507Y321933D01*
Y321297D01*
X73144Y320660D01*
X73780D01*
X77194Y324075D01*
X77830D01*
X78467Y323438D01*
Y322802D01*
X75053Y319387D01*
Y318751D01*
X75690Y318114D01*
X76326D01*
X79740Y321529D01*
X80376D01*
X81013Y320892D01*
Y320256D01*
X77599Y316841D01*
Y316205D01*
X78236Y315568D01*
X78872D01*
X82286Y318983D01*
X82922D01*
X83559Y318346D01*
Y317710D01*
X80145Y314295D01*
Y313659D01*
X80782Y313022D01*
X81418D01*
X84832Y316437D01*
X85468D01*
X86105Y315800D01*
Y315164D01*
X82691Y311749D01*
Y311113D01*
X83328Y310476D01*
X83964D01*
X87320Y313834D01*
X87956D01*
X88778Y313012D01*
Y307817D01*
X87424Y306463D01*
X83336D01*
X82917Y306044D01*
Y305082D01*
X83336Y304663D01*
X92892D01*
X93342Y304213D01*
Y303313D01*
X92892Y302863D01*
X83668D01*
X83218Y302413D01*
Y301513D01*
X83668Y301063D01*
X92892D01*
X93342Y300613D01*
Y299713D01*
X92892Y299263D01*
X86084D01*
X85634Y298813D01*
Y297913D01*
X86084Y297463D01*
X92892D01*
X93342Y297013D01*
Y296113D01*
X92892Y295663D01*
X90544D01*
X90094Y295213D01*
Y294313D01*
X90544Y293863D01*
X92892D01*
X93342Y293413D01*
Y290151D01*
X98035Y285458D01*
X109012D01*
X112520Y281950D01*
X118468D01*
X119564Y280854D01*
Y280853D01*
X124874Y275543D01*
Y273953D01*
G01X135592Y257933D02*
X134919Y258606D01*
Y258722D01*
X130076Y263565D01*
Y291176D01*
X129999Y291253D01*
Y291517D01*
X74690Y346826D01*
X74054D01*
X70875Y343647D01*
X70239D01*
X69602Y344284D01*
Y344920D01*
X72781Y348099D01*
Y348735D01*
X72144Y349372D01*
X71508D01*
X68329Y346193D01*
X67693D01*
X67056Y346830D01*
Y347466D01*
X70235Y350645D01*
Y351281D01*
X47839Y373677D01*
Y384946D01*
X40273Y392512D01*
Y449583D01*
X38566Y451290D01*
G01X18448Y402542D02*
Y402408D01*
X18226Y402186D01*
Y384219D01*
X20003Y382434D01*
X20948Y381489D01*
X21296Y381140D01*
Y352849D01*
X47380Y326765D01*
X49996D01*
Y326764D01*
X50798Y327566D01*
X55667D01*
X58668Y324565D01*
Y320289D01*
X56940Y318561D01*
Y317205D01*
X57318Y316828D01*
X69717Y304429D01*
Y295103D01*
X82810Y282010D01*
Y275866D01*
X87591Y271085D01*
X99905D01*
X100921Y272101D01*
X105050D01*
X106467Y270684D01*
X114229D01*
G01X26972Y399588D02*
Y396565D01*
X28526Y395011D01*
Y387921D01*
X31283Y385164D01*
Y365954D01*
X68568Y328669D01*
Y319582D01*
X79617Y308533D01*
Y299208D01*
X92710Y286115D01*
Y283123D01*
X93675Y282158D01*
X107644D01*
X111898Y277904D01*
Y276047D01*
X112042Y275903D01*
G01X24357Y423051D02*
Y428477D01*
X33242Y437362D01*
Y446043D01*
X30248Y449037D01*
X26996D01*
X26499Y448540D01*
Y444362D01*
X28336Y442525D01*
Y435640D01*
X24990Y432294D01*
Y432293D01*
X22390Y429693D01*
Y424903D01*
X21823Y424336D01*
Y398809D01*
X21526Y398512D01*
Y385585D01*
X24683Y382428D01*
Y354130D01*
X47947Y330866D01*
X57035D01*
X61968Y325933D01*
Y316846D01*
X73017Y305797D01*
Y296471D01*
X74406Y295083D01*
Y295082D01*
X86110Y283378D01*
Y277234D01*
X88959Y274385D01*
X98537D01*
X99553Y275401D01*
X106419D01*
X107742Y274078D01*
X112797D01*
X112878Y274159D01*
X115219D01*
X117027Y275967D01*
Y278475D01*
G01X19757Y418538D02*
Y408986D01*
X20173Y408570D01*
Y399493D01*
X19876Y399196D01*
Y384901D01*
X23033Y381744D01*
Y353446D01*
X47263Y329216D01*
X56351D01*
X60318Y325249D01*
Y319605D01*
X59405Y318692D01*
Y317075D01*
X71367Y305113D01*
Y295787D01*
X72756Y294399D01*
Y294398D01*
X84460Y282694D01*
Y276550D01*
X88275Y272735D01*
X99221D01*
X100237Y273751D01*
X105734D01*
X107057Y272428D01*
X113482D01*
X113563Y272509D01*
X115912D01*
X116362Y272059D01*
Y269134D01*
X115912Y268684D01*
X110926D01*
X110476Y268234D01*
Y261624D01*
X110026Y261174D01*
X108770D01*
X108320Y260724D01*
Y258341D01*
X108770Y257891D01*
X112962D01*
X120057Y264986D01*
X125610D01*
X126060Y265436D01*
Y267454D01*
X125610Y267904D01*
X119646D01*
X119196Y268354D01*
Y273520D01*
X118219Y274497D01*
G01X121599Y274869D02*
Y276484D01*
X117914Y280169D01*
Y280170D01*
X117784Y280300D01*
X111836D01*
X108328Y283808D01*
X97351D01*
X81267Y299892D01*
Y309217D01*
X70218Y320266D01*
Y329353D01*
X32933Y366638D01*
Y385848D01*
X30176Y388605D01*
Y395695D01*
X28697Y397174D01*
Y412131D01*
X29147Y412581D01*
X37709D01*
X38623Y413495D01*
Y415301D01*
X38173Y415751D01*
X33399D01*
X32949Y416201D01*
Y417101D01*
X33399Y417551D01*
X38173D01*
X38623Y418001D01*
Y418901D01*
X38173Y419351D01*
X33399D01*
X32949Y419801D01*
Y420701D01*
X33399Y421151D01*
X38173D01*
X38623Y421601D01*
Y422501D01*
X38173Y422951D01*
X33399D01*
X32949Y423401D01*
Y424301D01*
X33399Y424751D01*
X38173D01*
X38623Y425201D01*
Y426101D01*
X38173Y426551D01*
X33399D01*
X32949Y427001D01*
Y427901D01*
X33399Y428351D01*
X38173D01*
X38623Y428801D01*
Y429701D01*
X38173Y430151D01*
X33399D01*
X32949Y430601D01*
Y431501D01*
X33399Y431951D01*
X38173D01*
X38623Y432401D01*
Y434294D01*
X37660Y435257D01*
X33471D01*
X29472Y431258D01*
Y428016D01*
G01X17936Y431103D02*
X20741Y433909D01*
Y434545D01*
X17748Y437537D01*
X17112D01*
X15328Y435753D01*
X12588D01*
X12138Y436203D01*
Y442324D01*
X14124Y444310D01*
X20589D01*
X25447Y439452D01*
Y436990D01*
X25473Y436964D01*
Y435111D01*
X20740Y430378D01*
Y425587D01*
X18799Y423646D01*
Y420095D01*
X18032Y419328D01*
Y408812D01*
X16576Y407356D01*
Y383536D01*
X18775Y381328D01*
X19298Y380805D01*
X19303Y380795D01*
Y365455D01*
X19302D01*
Y351030D01*
X57816Y312516D01*
X59084D01*
X59131Y312469D01*
X59343D01*
X68067Y303744D01*
Y294419D01*
X81160Y281326D01*
Y275182D01*
X86907Y269435D01*
X100589D01*
X101605Y270451D01*
X104366D01*
X107887Y266930D01*
Y266647D01*
G01X64055Y389700D02*
X69227D01*
X70169Y388758D01*
X78597D01*
X106480Y360875D01*
X228906D01*
X229731Y361700D01*
X271445D01*
X295420Y385675D01*
X473838D01*
G01X248286Y489208D02*
X248408D01*
X240400Y481200D01*
Y479125D01*
X212975Y451700D01*
X207833D01*
X205532Y449399D01*
X195135D01*
X194365Y450169D01*
X167408D01*
X166296Y451281D01*
X152855D01*
X147388Y445814D01*
Y444868D01*
X146378Y443858D01*
X141499D01*
X135589Y437948D01*
Y437005D01*
X134092Y435508D01*
X133149D01*
X132139Y434498D01*
Y433555D01*
X122281Y423697D01*
X121338D01*
X120328Y422687D01*
Y421748D01*
X114454Y415874D01*
X78290D01*
X77214Y414798D01*
Y414301D01*
X75259Y412346D01*
X74971D01*
X72724Y410099D01*
Y404332D01*
X70779Y402387D01*
G01X43719Y414419D02*
X49039D01*
X49489Y413969D01*
Y411059D01*
X49039Y410609D01*
X43312D01*
X42862Y410159D01*
Y409259D01*
X43312Y408809D01*
X49039D01*
X49489Y408359D01*
Y406999D01*
X49039Y406549D01*
X43456D01*
X43006Y406099D01*
Y405199D01*
X43456Y404749D01*
X49039D01*
X49489Y404299D01*
Y403399D01*
X49039Y402949D01*
X43456D01*
X43006Y402499D01*
Y401599D01*
X43456Y401149D01*
X49039D01*
X49489Y400699D01*
Y399799D01*
X49039Y399349D01*
X43456D01*
X43006Y398899D01*
Y397999D01*
X43456Y397549D01*
X49039D01*
X49489Y397099D01*
Y396199D01*
X49039Y395749D01*
X43456D01*
X43006Y395299D01*
Y394399D01*
X43456Y393949D01*
X49039D01*
X49489Y393499D01*
Y374361D01*
X53685Y370165D01*
X65391Y358460D01*
X68375D01*
X94507Y332328D01*
Y332308D01*
X131726Y295089D01*
Y274060D01*
X133988Y271798D01*
Y266511D01*
X132704Y265227D01*
Y263714D01*
X136243Y260175D01*
X138228D01*
G01X637200Y393900D02*
X635800Y392500D01*
X503200D01*
X491160Y380460D01*
X473349D01*
X473209Y380600D01*
X297200D01*
X275000Y358400D01*
X231100D01*
X230174Y357474D01*
X87826D01*
X55486Y389814D01*
X53976D01*
G01X74894Y398251D02*
X72977Y396334D01*
Y393585D01*
X74030Y392532D01*
X77110D01*
X78571Y391071D01*
X79948Y389695D01*
X84811D01*
X104996Y369510D01*
X270133D01*
X291723Y391100D01*
X467821D01*
X504900Y428179D01*
X508306D01*
G01X474106Y382285D02*
X296425D01*
X274190Y360050D01*
X230415D01*
X229590Y359225D01*
X100975D01*
X80300Y379900D01*
Y381286D01*
X76685Y384901D01*
X64233D01*
X62330Y386804D01*
Y399414D01*
X62031Y399713D01*
G01X74836Y453477D02*
X76300Y454941D01*
Y468341D01*
X76530Y468571D01*
Y482030D01*
X78700Y484200D01*
Y486423D01*
X81400Y489123D01*
Y499200D01*
X97700Y515500D01*
Y525000D01*
X105850Y533150D01*
X208150D01*
X226200Y551200D01*
X262058D01*
X278594Y534664D01*
X281825D01*
X283657Y532832D01*
G01X632600Y555200D02*
X630358D01*
X629108Y556450D01*
X528508D01*
X519047Y565911D01*
X215011D01*
X194700Y545600D01*
X97700D01*
X77879Y525779D01*
Y512587D01*
X62000Y496708D01*
Y484537D01*
X59980Y482517D01*
G01X82564Y449659D02*
X81005Y448100D01*
X78118D01*
X76420Y449798D01*
Y449975D01*
X75548Y450848D01*
X74644Y451752D01*
X74121D01*
G01X73136Y455114D02*
X72633Y455617D01*
Y468879D01*
X72634Y468880D01*
Y483500D01*
X71973Y484161D01*
Y496115D01*
X89029Y513171D01*
Y522770D01*
X103709Y537450D01*
X201508D01*
X222508Y558450D01*
X277250D01*
X285000Y550700D01*
X469239D01*
X476600Y558061D01*
X497600D01*
X509309Y546352D01*
X638610D01*
X641583Y549325D01*
X643833D01*
G01X280259Y532714D02*
X277786D01*
X261250Y549250D01*
X227008D01*
X208958Y531200D01*
X106658D01*
X99650Y524192D01*
Y514692D01*
X83129Y498171D01*
Y488094D01*
X80653Y485618D01*
Y471153D01*
X77325Y467825D01*
Y454364D01*
X77029Y454068D01*
Y451629D01*
X78754Y449904D01*
G01X98288Y441609D02*
X96292Y443605D01*
X77695D01*
X72900Y448400D01*
Y451402D01*
X72302Y452000D01*
G01X70600Y455318D02*
X68629Y457289D01*
Y458500D01*
X63950Y463179D01*
Y495900D01*
X79829Y511779D01*
Y524971D01*
X98508Y543650D01*
X195508D01*
X215819Y563961D01*
X518239D01*
X527700Y554500D01*
X628300D01*
X629550Y553250D01*
X634350D01*
X636200Y555100D01*
G01X640100Y550600D02*
X637802Y548302D01*
X510117D01*
X498408Y560011D01*
X475792D01*
X468431Y552650D01*
X285808D01*
X278058Y560400D01*
X221700D01*
X200700Y539400D01*
X102901D01*
X87079Y523578D01*
Y513979D01*
X70023Y496923D01*
Y483977D01*
X67112Y481066D01*
G01X316982Y818335D02*
X318338Y816979D01*
Y792055D01*
X90127Y563844D01*
Y562007D01*
X47307Y519187D01*
Y465104D01*
G01X296982Y818335D02*
X301647Y823000D01*
X309000D01*
X310900Y821100D01*
Y795258D01*
X71604Y555962D01*
Y546133D01*
X45482Y520011D01*
Y464348D01*
X49030Y460800D01*
X51300D01*
X72300Y439800D01*
X81013D01*
X82573Y441360D01*
G01X306982Y818335D02*
Y813582D01*
X301200Y807800D01*
Y787892D01*
X43832Y530524D01*
Y480595D01*
X40587Y477350D01*
Y462653D01*
X44628Y458612D01*
X47700D01*
X70382Y435930D01*
X81295D01*
X85000Y439635D01*
X99073D01*
X100500Y441062D01*
Y444000D01*
X99095Y445405D01*
X98280D01*
G01X286982Y818335D02*
X287560Y817757D01*
Y779286D01*
X91386Y583112D01*
X90108D01*
X89098Y582102D01*
Y578125D01*
X42182Y531209D01*
Y484463D01*
X29064Y471345D01*
G01X55295Y479672D02*
X52800Y482167D01*
Y506800D01*
X57928Y511928D01*
Y521224D01*
X336982Y800278D01*
Y818335D01*
G01X326982D02*
Y792612D01*
X49558Y515188D01*
Y472355D01*
X68380Y453533D01*
X70602D01*
G01X159768Y238444D02*
Y238477D01*
X149325Y248920D01*
X139082D01*
X137809Y247647D01*
G01X171762Y258345D02*
X166779Y253362D01*
X130260D01*
X126651Y256971D01*
Y258225D01*
X126611Y258265D01*
G01X304000Y538500D02*
X303500D01*
X260451Y495451D01*
Y491751D01*
X243775Y475075D01*
Y467625D01*
X222900Y446750D01*
X214950D01*
X205301Y437101D01*
X178036D01*
X175692Y439445D01*
X160708D01*
X159211Y437948D01*
Y437005D01*
X158064Y435858D01*
X139739D01*
X135452Y431571D01*
X133149D01*
X128202Y426624D01*
Y425681D01*
X122281Y419760D01*
X121338D01*
X120328Y418750D01*
Y417811D01*
X114768Y412251D01*
X80984D01*
X79016Y410283D01*
G01X137570Y421843D02*
X139786Y419627D01*
Y391914D01*
X158890Y372810D01*
X268047D01*
X290194Y394957D01*
X390604D01*
X485697Y490050D01*
X493816D01*
X503316Y499550D01*
X679920D01*
X680499Y500129D01*
X745729D01*
X752100Y506500D01*
G01X749500Y508800D02*
X742479Y501779D01*
X679815D01*
X679236Y501200D01*
X498936D01*
X496967Y503169D01*
X457910D01*
X455864Y501123D01*
X380621D01*
X314367Y434869D01*
Y421464D01*
X267363Y374460D01*
X159940D01*
X144012Y390388D01*
Y418792D01*
X144037Y418817D01*
Y420355D01*
X145561Y421879D01*
G01X149663Y410083D02*
X147706Y408126D01*
Y390124D01*
X161720Y376110D01*
X266679D01*
X312717Y422148D01*
Y435553D01*
X379937Y502773D01*
X455180D01*
X457226Y504819D01*
X497651D01*
X499620Y502850D01*
X678552D01*
X679131Y503429D01*
X740429D01*
X742000Y505000D01*
G01X756400Y508100D02*
X746779Y498479D01*
X681183D01*
X680604Y497900D01*
X504000D01*
X494499Y488399D01*
X493133D01*
X493132Y488400D01*
X490132D01*
X394659Y392927D01*
X290678D01*
X268911Y371160D01*
X157340D01*
X136076Y392424D01*
Y416166D01*
X138061Y418151D01*
G01X232200Y492100D02*
X230359Y490259D01*
X193041D01*
X188127Y495173D01*
X142273D01*
X135950Y488850D01*
Y478650D01*
X132900Y475600D01*
X128600D01*
X124332Y471332D01*
Y463432D01*
X111797Y450897D01*
X96229D01*
X94518Y449186D01*
G01X86768Y449383D02*
X89132Y451747D01*
X111107D01*
X116950Y457590D01*
Y457653D01*
X120200Y460903D01*
Y470100D01*
X121532Y471432D01*
X122832D01*
X131700Y480300D01*
Y489500D01*
X139323Y497123D01*
X188935D01*
X193849Y492209D01*
X228479D01*
X231739Y495469D01*
G01X145675Y437720D02*
X151402Y443447D01*
X162371D01*
X163645Y442173D01*
X180479D01*
X180701Y441951D01*
X182817D01*
X182917Y442051D01*
X197349D01*
X198014Y442716D01*
X201206D01*
X202764Y444274D01*
G01X275500Y415400D02*
X275300Y415200D01*
X248909D01*
X243698Y420411D01*
X218647D01*
X214826Y416590D01*
X202918D01*
X198475Y412147D01*
X183560D01*
X182648Y411235D01*
X180155D01*
X180105Y411185D01*
X168123D01*
X167394Y411914D01*
X164269D01*
X164159Y412024D01*
X160927D01*
X159552Y413399D01*
Y414288D01*
X157422Y416418D01*
X156686D01*
X155031Y418073D01*
Y418707D01*
X153850Y419888D01*
X153193D01*
X149384Y423697D01*
X144231D01*
X141775Y426153D01*
G01X141763Y437883D02*
X143638Y439758D01*
X146378D01*
X151691Y445071D01*
Y446254D01*
X152760Y447323D01*
X175100D01*
X176296Y448519D01*
X193681D01*
X194451Y447749D01*
X206216D01*
X208517Y450050D01*
X221532D01*
X233941Y462459D01*
Y463812D01*
X235069Y464940D01*
G01X141863Y445583D02*
X143880Y447600D01*
X146220D01*
X147488Y448868D01*
Y449848D01*
X152837Y455197D01*
X173949D01*
X177095Y452051D01*
X195400D01*
G01X756272Y534995D02*
X747309Y543958D01*
X691284D01*
X687693Y547549D01*
X665367D01*
X650823Y533005D01*
X340481D01*
X267239Y459763D01*
Y456373D01*
X258467Y447601D01*
X250633D01*
X248132Y445100D01*
X217029D01*
X204345Y432416D01*
X196884D01*
X196061Y433239D01*
X176117D01*
X175876Y432998D01*
X172522D01*
X170012Y435508D01*
X160708D01*
X159698Y434498D01*
Y433555D01*
X158201Y432058D01*
X148897D01*
X147172Y433783D01*
X145675D01*
G01X228001Y474064D02*
X228000D01*
Y474100D01*
X227668Y474432D01*
X226252D01*
X211363Y459543D01*
X193391D01*
X192234Y460700D01*
X166985D01*
X165878Y459593D01*
X156974D01*
X156499Y459118D01*
X147578D01*
X141649Y453189D01*
G01X176751Y387090D02*
X206546D01*
X211179Y391723D01*
X265012D01*
X293739Y420450D01*
Y431057D01*
X302831Y440149D01*
X307583D01*
X375553Y508119D01*
X499019D01*
X500988Y506150D01*
X677184D01*
X677763Y506729D01*
X737097D01*
X743911Y513543D01*
X757848D01*
G01X737297Y517903D02*
X734694Y515300D01*
X714900D01*
X712975Y517225D01*
X706832D01*
X706622Y517015D01*
X485404D01*
X482560Y519859D01*
X363931D01*
X296072Y452000D01*
X289000D01*
X284536Y447536D01*
Y440464D01*
X277579Y433507D01*
Y414879D01*
X275257Y412557D01*
X249002D01*
X244959Y416600D01*
X223863D01*
X220200Y412937D01*
Y412500D01*
X216602Y408902D01*
X200251D01*
X200084Y408735D01*
X183091D01*
X182291Y409535D01*
X180861D01*
X179483Y408157D01*
X161177D01*
X157251Y412083D01*
Y414149D01*
G01X756523Y520272D02*
X745972D01*
X737625Y511925D01*
X703707D01*
X701917Y513715D01*
X371729D01*
X312365Y454351D01*
X309117D01*
X290439Y435673D01*
Y421818D01*
X266096Y397475D01*
X255043D01*
X254510Y398008D01*
X220240D01*
X219246Y399002D01*
X204891D01*
X200400Y394511D01*
X161477D01*
G01X725100Y519600D02*
X685223D01*
X674677Y530146D01*
X664344D01*
X657998Y523800D01*
X486877D01*
X484871Y521794D01*
X363532D01*
X295969Y454231D01*
X288897D01*
X282886Y448220D01*
Y441148D01*
X265685Y423947D01*
X217515D01*
X213517Y419949D01*
X198114D01*
X193612Y415447D01*
X182086D01*
X180809Y414170D01*
G01X269840Y386256D02*
X267672Y388423D01*
X212547D01*
X207307Y383183D01*
X161103D01*
X151687Y392599D01*
Y411626D01*
X149362Y413951D01*
G01X157554Y402251D02*
X159508Y400297D01*
X161610D01*
X163633Y398274D01*
Y397638D01*
X165625Y395646D01*
X183293D01*
X187132Y399485D01*
X202636D01*
X203803Y400652D01*
X219930D01*
X220709Y399873D01*
X233880D01*
X235382Y401375D01*
X260320D01*
X261300Y402355D01*
G01X220768Y418393D02*
X218963D01*
X215376Y414806D01*
X210001D01*
X207285Y412090D01*
X201105D01*
X199400Y410385D01*
X180508D01*
X180005Y409882D01*
X165266D01*
G01X264124Y408219D02*
X261543Y410800D01*
X248425D01*
X244275Y414950D01*
X224547D01*
X221850Y412253D01*
Y411816D01*
X217286Y407252D01*
X201067D01*
X199900Y406085D01*
X180450D01*
X180293Y406242D01*
X161889D01*
X155526Y412605D01*
Y415772D01*
X153201Y418097D01*
G01X258267Y408800D02*
X257800Y408333D01*
X248558D01*
X243591Y413300D01*
X225231D01*
X223500Y411569D01*
Y411132D01*
X217970Y405602D01*
X201751D01*
X200584Y404435D01*
X180897D01*
X179940Y405392D01*
X161059D01*
X156399Y410052D01*
X153528D01*
G01X157401Y418143D02*
X159232D01*
X161536Y415839D01*
X161992D01*
X163612Y414219D01*
Y413774D01*
X164622Y412764D01*
X174019D01*
X174748Y412035D01*
X179752D01*
X179802Y412085D01*
X181164D01*
X182876Y413797D01*
X194902D01*
X199404Y418299D01*
X200918D01*
X200977Y418240D01*
X214142D01*
X217963Y422061D01*
X256364D01*
X257184Y421241D01*
G01X233400Y409700D02*
X231302Y407602D01*
X222677D01*
X219027Y403952D01*
X202435D01*
X201268Y402785D01*
X181443D01*
X179457Y400799D01*
X167998D01*
X165455Y398256D01*
G01X762275Y512870D02*
X762070D01*
X760519Y511319D01*
X744021D01*
X737781Y505079D01*
X678447D01*
X677868Y504500D01*
X500304D01*
X498335Y506469D01*
X376237D01*
X307917Y438149D01*
X303165D01*
X295389Y430373D01*
Y419766D01*
X265696Y390073D01*
X211863D01*
X206623Y384833D01*
X175100D01*
X167481Y392452D01*
X161096D01*
X159299Y394249D01*
Y396625D01*
X157411Y398513D01*
G01X744073Y522097D02*
X735551Y513575D01*
X704391D01*
X702601Y515365D01*
X371045D01*
X311681Y456001D01*
X308433D01*
X288789Y436357D01*
Y422502D01*
X271987Y405700D01*
X244825D01*
X242600Y403475D01*
X229330D01*
X228000Y404805D01*
X222214D01*
X219711Y402302D01*
X203119D01*
X201952Y401135D01*
X181008D01*
X179375Y399502D01*
X170316D01*
X169113Y398299D01*
G01X178031Y390023D02*
X180208Y392200D01*
X209000D01*
X210400Y393600D01*
X264555D01*
X292089Y421134D01*
Y434989D01*
X309800Y452700D01*
X313048D01*
X370117Y509769D01*
X499703D01*
X501672Y507800D01*
X676500D01*
X677079Y508379D01*
X736413D01*
X744337Y516303D01*
X755862D01*
G01X210772Y431456D02*
X210082Y430766D01*
X196100D01*
X195277Y431589D01*
X161669D01*
X158201Y428121D01*
X155274D01*
X153549Y429846D01*
G01X165621Y418066D02*
X167402Y419847D01*
X178600D01*
X179700Y418747D01*
X192244D01*
X196746Y423249D01*
X212149D01*
X216147Y427247D01*
X237413D01*
X247966Y437800D01*
X255668D01*
X274189Y456321D01*
Y456739D01*
X284099Y466649D01*
X293931D01*
X298115Y470833D01*
Y477108D01*
X346101Y525094D01*
X483503D01*
X485509Y527100D01*
X653305D01*
X659651Y533446D01*
X676046D01*
X682395Y527097D01*
X704232D01*
X708535Y531400D01*
X720900D01*
X721875Y530425D01*
X743637D01*
X751965Y522097D01*
G01X747886D02*
X746061Y523922D01*
X743316D01*
X742343Y522949D01*
X713817D01*
X710841Y525925D01*
X705394D01*
X701500Y522031D01*
X685126D01*
X675361Y531796D01*
X660335D01*
X653989Y525450D01*
X486193D01*
X484187Y523444D01*
X353126D01*
X294615Y464933D01*
X285964D01*
X257031Y436000D01*
X248500D01*
X238097Y425597D01*
X216831D01*
X212833Y421599D01*
X197430D01*
X192928Y417097D01*
X178159D01*
X177297Y416235D01*
X165012D01*
X163896Y417351D01*
Y418375D01*
X162113Y420158D01*
X156748D01*
X155738Y421168D01*
Y422223D01*
X154264Y423697D01*
X153321D01*
X151517Y425501D01*
Y426755D01*
X149612Y428660D01*
Y429846D01*
G01X752874Y534854D02*
X750687Y537041D01*
X747866D01*
X747700Y536875D01*
X707457D01*
X706857Y536275D01*
X696633D01*
X687009Y545899D01*
X667436D01*
X652892Y531355D01*
X341165D01*
X268889Y459079D01*
Y455689D01*
X259151Y445951D01*
X251317D01*
X235913Y430547D01*
X214779D01*
X210781Y426549D01*
X189282D01*
X187125Y424392D01*
X179325D01*
X177033Y422100D01*
X172200D01*
X170603Y423697D01*
X156503D01*
X154291Y425909D01*
X153549D01*
G01X161746Y421972D02*
X162920D01*
X164645Y420247D01*
X166075D01*
X166525Y420697D01*
X191860D01*
X196062Y424899D01*
X211465D01*
X215463Y428897D01*
X236597D01*
X252000Y444300D01*
X259834D01*
X272539Y457005D01*
Y458072D01*
X341211Y526744D01*
X482819D01*
X484825Y528750D01*
X652621D01*
X664585Y540714D01*
X675800D01*
X681889Y534625D01*
X748902D01*
X749493Y535216D01*
G01X200453Y439066D02*
X200138Y438751D01*
X178811D01*
X177267Y440295D01*
X156124D01*
X153549Y437720D01*
G01X242100Y489000D02*
X232000Y478900D01*
Y474650D01*
X211445Y454095D01*
X205789D01*
X203186Y451492D01*
G01X184750Y427953D02*
X184057D01*
X181271Y430739D01*
X173613D01*
X170828Y427954D01*
X167440D01*
X165804Y429590D01*
X165411D01*
G01X208947Y443700D02*
X207173D01*
X204364Y440891D01*
X198523D01*
X198033Y440401D01*
X181048D01*
X180304Y441145D01*
X155536D01*
X154388Y439997D01*
X151889D01*
X149612Y437720D01*
G01X196803Y444462D02*
X198440Y446099D01*
X206900D01*
X209201Y448400D01*
X222216D01*
X242050Y468234D01*
Y479232D01*
X258800Y495982D01*
Y496382D01*
X303343Y540925D01*
X308800D01*
G01X201400Y434400D02*
X200911Y434889D01*
X175327D01*
X175161Y434723D01*
G01X182060Y443776D02*
X181884Y443600D01*
X163421D01*
X161423Y445598D01*
G01X157486Y425909D02*
X159085Y427508D01*
X166300D01*
X167883Y425925D01*
X175257D01*
X175707Y425475D01*
X178457D01*
X178465Y425483D01*
X184862D01*
X187578Y428199D01*
X210097D01*
X214270Y432372D01*
X234672D01*
X235600Y433300D01*
G01X208632Y457048D02*
X208294Y456710D01*
X192892D01*
X191549Y455367D01*
X177709D01*
X174173Y458903D01*
X168230D01*
X166688Y457361D01*
X165217D01*
G01X228400Y486400D02*
X222585Y480585D01*
X181938D01*
X175438Y474085D01*
X168728D01*
X166075Y471432D01*
X163148D01*
X161423Y473157D01*
G01X255010Y367624D02*
X256835Y365799D01*
X272062D01*
X295331Y389068D01*
X473605D01*
G01X702000Y546581D02*
X700919D01*
X694554Y552946D01*
X673446D01*
X671890Y551390D01*
X652873D01*
X645320Y543837D01*
X643837D01*
X639200Y539200D01*
X508342D01*
X498823Y548719D01*
X476200D01*
X468532Y541051D01*
X315049D01*
X311425Y544675D01*
X302835D01*
X257160Y499000D01*
X239100D01*
X232200Y492100D01*
G01X702400Y550600D02*
X699658D01*
X695362Y554896D01*
X672638D01*
X671082Y553340D01*
X652065D01*
X644512Y545787D01*
X643029D01*
X638449Y541207D01*
X509093D01*
X499631Y550669D01*
X475392D01*
X467724Y543001D01*
X316099D01*
X312475Y546625D01*
X302027D01*
X256352Y500950D01*
X237220D01*
X231739Y495469D01*
G01X324400Y570500D02*
X326200Y572300D01*
X737200D01*
X742000Y577100D01*
X742600D01*
G01X702400Y431500D02*
X698000Y427100D01*
X561680D01*
X500458Y488322D01*
X498994D01*
G01X698300Y431600D02*
X695750Y429050D01*
X562488D01*
X501802Y489736D01*
Y490240D01*
G01X504500Y479500D02*
X562700Y421300D01*
X629800D01*
X680500Y370600D01*
X756700D01*
G01X758200Y338900D02*
X728500Y368600D01*
X680166D01*
X629116Y419650D01*
X561950D01*
X504450Y477150D01*
X501750D01*
X501700Y477200D01*
G01X762900Y387400D02*
X755700Y394600D01*
X662100D01*
G01X685799Y770894D02*
X670100Y755195D01*
Y732578D01*
X668987Y731465D01*
G01X685799Y770894D02*
Y777899D01*
X733066Y825166D01*
Y836450D01*
G01X766358Y564600D02*
Y564642D01*
X728500Y602500D01*
Y765600D01*
X734891Y771991D01*
Y837206D01*
X729820Y842277D01*
X726776D01*
G01X727700Y584400D02*
X742500D01*
X758400Y568500D01*
G54D16*
X29528Y19685D03*
X76772D03*
X108268Y905512D03*
X155512D03*
G54D17*
X53547Y322486D03*
Y302486D03*
X182681Y580832D03*
Y560832D03*
G54D18*
X109410Y796831D03*
Y876397D03*
X168465Y796831D03*
Y876397D03*
G54D19*
X286982Y828335D03*
X276982D03*
X286982Y818335D03*
X276982D03*
X356982Y828335D03*
X346982D03*
X336982D03*
X326982D03*
X316982D03*
X306982D03*
X296982D03*
X356982Y818335D03*
X346982D03*
X336982D03*
X326982D03*
X316982D03*
X306982D03*
X296982D03*
X366982Y828335D03*
Y818335D03*
M02*
